FILE_TYPE = MACRO_DRAWING;
SET COLOR_WIRE YELLOW;
SET COLOR_PROP ORANGE;
SET COLOR_DOT WHITE;
SET COLOR_ARC YELLOW;
SET COLOR_BODY GREEN;
SET COLOR_NOTE PURPLE;
SET PROP_DISPLAY VALUE;
SET PAGE_NUMBER P94;
FORCEADD OFFPAGE..5
(-8250 1875);
FORCEPROP 2 LAST $XR0 19 
J 0
(-8474 1875);
DISPLAY 0.638298 (-8474 1875);
PAINT MONO (-8474 1875);
FORCEPROP 2 LAST PATH I1
J 0
(-8200 1950);
DISPLAY 1.021277 (-8200 1950);
DISPLAY INVISIBLE (-8200 1950);
FORCEPROP 1 LAST COMMENT_BODY TRUE
J 0
(-8150 1800);
DISPLAY 0.872340 (-8150 1800);
PAINT GREEN (-8150 1800);
DISPLAY INVISIBLE (-8150 1800);
FORCEPROP 1 LAST OFFPAGE TRUE
J 0
(-7925 1750);
DISPLAY 0.872340 (-7925 1750);
PAINT GREEN (-7925 1750);
DISPLAY INVISIBLE (-7925 1750);
FORCEPROP 2 LAST CDS_LIB mstr_standard
J 0
(-8250 1875);
DISPLAY 0.808511 (-8250 1875);
DISPLAY INVISIBLE (-8250 1875);
FORCEADD OFFPAGE..6
(-8250 3525);
FORCEPROP 2 LAST $XR0 19 
J 0
(-8529 3525);
DISPLAY 0.638298 (-8529 3525);
PAINT MONO (-8529 3525);
FORCEPROP 2 LAST PATH I10
J 0
(-8200 3600);
DISPLAY 1.021277 (-8200 3600);
DISPLAY INVISIBLE (-8200 3600);
FORCEPROP 1 LAST COMMENT_BODY TRUE
J 0
(-8150 3450);
DISPLAY 0.872340 (-8150 3450);
PAINT GREEN (-8150 3450);
DISPLAY INVISIBLE (-8150 3450);
FORCEPROP 1 LAST OFFPAGE TRUE
J 0
(-7925 3400);
DISPLAY 0.872340 (-7925 3400);
PAINT GREEN (-7925 3400);
DISPLAY INVISIBLE (-7925 3400);
FORCEPROP 2 LAST CDS_LIB mstr_standard
J 0
(-8250 3525);
DISPLAY 0.723404 (-8250 3525);
PAINT MONO (-8250 3525);
DISPLAY INVISIBLE (-8250 3525);
FORCEADD TAP..1
(-5950 4075);
FORCEPROP 3 LASTPIN (-6000 4075) SIG_NAME M_J_CPU0_SA_DQ<6>
J 0
(-5990 4085);
DISPLAY 0.659574 (-5990 4085);
PAINT MONO (-5990 4085);
DISPLAY INVISIBLE (-5990 4085);
FORCEPROP 1 LASTPIN (-6000 4075) BN 6
J 0
(-6012 4083);
DISPLAY 0.489362 (-6012 4083);
PAINT GREEN (-6012 4083);
FORCEPROP 2 LAST CDS_LIB mstr_standard
J 0
(-5950 4075);
DISPLAY 0.723404 (-5950 4075);
PAINT MONO (-5950 4075);
DISPLAY INVISIBLE (-5950 4075);
FORCEPROP 1 LAST BODY_TYPE PLUMBING
J 0
(-5950 4125);
DISPLAY 0.872340 (-5950 4125);
PAINT GREEN (-5950 4125);
DISPLAY INVISIBLE (-5950 4125);
FORCEPROP 1 LAST HDL_TAP TRUE
J 0
(-5625 3950);
DISPLAY 0.872340 (-5625 3950);
DISPLAY INVISIBLE (-5625 3950);
FORCEPROP 1 LAST PATH I100
J 0
(-5952 4075);
DISPLAY 0.872340 (-5952 4075);
PAINT GREEN (-5952 4075);
DISPLAY INVISIBLE (-5952 4075);
FORCEADD TAP..1
(-5950 4125);
FORCEPROP 3 LASTPIN (-6000 4125) SIG_NAME M_J_CPU0_SA_DQ<7>
J 0
(-5990 4135);
DISPLAY 0.659574 (-5990 4135);
PAINT MONO (-5990 4135);
DISPLAY INVISIBLE (-5990 4135);
FORCEPROP 1 LASTPIN (-6000 4125) BN 7
J 0
(-6012 4133);
DISPLAY 0.489362 (-6012 4133);
PAINT GREEN (-6012 4133);
FORCEPROP 2 LAST CDS_LIB mstr_standard
J 0
(-5950 4125);
DISPLAY 0.723404 (-5950 4125);
PAINT MONO (-5950 4125);
DISPLAY INVISIBLE (-5950 4125);
FORCEPROP 1 LAST BODY_TYPE PLUMBING
J 0
(-5950 4175);
DISPLAY 0.872340 (-5950 4175);
PAINT GREEN (-5950 4175);
DISPLAY INVISIBLE (-5950 4175);
FORCEPROP 1 LAST HDL_TAP TRUE
J 0
(-5625 4000);
DISPLAY 0.872340 (-5625 4000);
DISPLAY INVISIBLE (-5625 4000);
FORCEPROP 1 LAST PATH I101
J 0
(-5952 4125);
DISPLAY 0.872340 (-5952 4125);
PAINT GREEN (-5952 4125);
DISPLAY INVISIBLE (-5952 4125);
FORCEADD TAP..1
(-5950 4275);
FORCEPROP 3 LASTPIN (-6000 4275) SIG_NAME M_J_CPU0_SA_DQ<10>
J 0
(-5990 4285);
DISPLAY 0.659574 (-5990 4285);
PAINT MONO (-5990 4285);
DISPLAY INVISIBLE (-5990 4285);
FORCEPROP 1 LASTPIN (-6000 4275) BN 10
J 0
(-6012 4283);
DISPLAY 0.489362 (-6012 4283);
PAINT GREEN (-6012 4283);
FORCEPROP 2 LAST CDS_LIB mstr_standard
J 0
(-5950 4275);
DISPLAY 0.723404 (-5950 4275);
PAINT MONO (-5950 4275);
DISPLAY INVISIBLE (-5950 4275);
FORCEPROP 1 LAST BODY_TYPE PLUMBING
J 0
(-5950 4325);
DISPLAY 0.872340 (-5950 4325);
PAINT GREEN (-5950 4325);
DISPLAY INVISIBLE (-5950 4325);
FORCEPROP 1 LAST HDL_TAP TRUE
J 0
(-5625 4150);
DISPLAY 0.872340 (-5625 4150);
DISPLAY INVISIBLE (-5625 4150);
FORCEPROP 1 LAST PATH I102
J 0
(-5952 4275);
DISPLAY 0.872340 (-5952 4275);
PAINT GREEN (-5952 4275);
DISPLAY INVISIBLE (-5952 4275);
FORCEADD TAP..1
(-5950 4225);
FORCEPROP 3 LASTPIN (-6000 4225) SIG_NAME M_J_CPU0_SA_DQ<9>
J 0
(-5990 4235);
DISPLAY 0.659574 (-5990 4235);
PAINT MONO (-5990 4235);
DISPLAY INVISIBLE (-5990 4235);
FORCEPROP 1 LASTPIN (-6000 4225) BN 9
J 0
(-6012 4233);
DISPLAY 0.489362 (-6012 4233);
PAINT GREEN (-6012 4233);
FORCEPROP 2 LAST CDS_LIB mstr_standard
J 0
(-5950 4225);
DISPLAY 0.723404 (-5950 4225);
PAINT MONO (-5950 4225);
DISPLAY INVISIBLE (-5950 4225);
FORCEPROP 1 LAST BODY_TYPE PLUMBING
J 0
(-5950 4275);
DISPLAY 0.872340 (-5950 4275);
PAINT GREEN (-5950 4275);
DISPLAY INVISIBLE (-5950 4275);
FORCEPROP 1 LAST HDL_TAP TRUE
J 0
(-5625 4100);
DISPLAY 0.872340 (-5625 4100);
DISPLAY INVISIBLE (-5625 4100);
FORCEPROP 1 LAST PATH I103
J 0
(-5952 4225);
DISPLAY 0.872340 (-5952 4225);
PAINT GREEN (-5952 4225);
DISPLAY INVISIBLE (-5952 4225);
FORCEADD TAP..1
(-5950 4175);
FORCEPROP 3 LASTPIN (-6000 4175) SIG_NAME M_J_CPU0_SA_DQ<8>
J 0
(-5990 4185);
DISPLAY 0.659574 (-5990 4185);
PAINT MONO (-5990 4185);
DISPLAY INVISIBLE (-5990 4185);
FORCEPROP 1 LASTPIN (-6000 4175) BN 8
J 0
(-6012 4183);
DISPLAY 0.489362 (-6012 4183);
PAINT GREEN (-6012 4183);
FORCEPROP 2 LAST CDS_LIB mstr_standard
J 0
(-5950 4175);
DISPLAY 0.723404 (-5950 4175);
PAINT MONO (-5950 4175);
DISPLAY INVISIBLE (-5950 4175);
FORCEPROP 1 LAST BODY_TYPE PLUMBING
J 0
(-5950 4225);
DISPLAY 0.872340 (-5950 4225);
PAINT GREEN (-5950 4225);
DISPLAY INVISIBLE (-5950 4225);
FORCEPROP 1 LAST HDL_TAP TRUE
J 0
(-5625 4050);
DISPLAY 0.872340 (-5625 4050);
DISPLAY INVISIBLE (-5625 4050);
FORCEPROP 1 LAST PATH I104
J 0
(-5952 4175);
DISPLAY 0.872340 (-5952 4175);
PAINT GREEN (-5952 4175);
DISPLAY INVISIBLE (-5952 4175);
FORCEADD TAP..1
(-5950 4325);
FORCEPROP 3 LASTPIN (-6000 4325) SIG_NAME M_J_CPU0_SA_DQ<11>
J 0
(-5990 4335);
DISPLAY 0.659574 (-5990 4335);
PAINT MONO (-5990 4335);
DISPLAY INVISIBLE (-5990 4335);
FORCEPROP 1 LASTPIN (-6000 4325) BN 11
J 0
(-6012 4333);
DISPLAY 0.489362 (-6012 4333);
PAINT GREEN (-6012 4333);
FORCEPROP 2 LAST CDS_LIB mstr_standard
J 0
(-5950 4325);
DISPLAY 0.723404 (-5950 4325);
PAINT MONO (-5950 4325);
DISPLAY INVISIBLE (-5950 4325);
FORCEPROP 1 LAST BODY_TYPE PLUMBING
J 0
(-5950 4375);
DISPLAY 0.872340 (-5950 4375);
PAINT GREEN (-5950 4375);
DISPLAY INVISIBLE (-5950 4375);
FORCEPROP 1 LAST HDL_TAP TRUE
J 0
(-5625 4200);
DISPLAY 0.872340 (-5625 4200);
DISPLAY INVISIBLE (-5625 4200);
FORCEPROP 1 LAST PATH I105
J 0
(-5952 4325);
DISPLAY 0.872340 (-5952 4325);
PAINT GREEN (-5952 4325);
DISPLAY INVISIBLE (-5952 4325);
FORCEADD TAP..1
(-5950 4375);
FORCEPROP 3 LASTPIN (-6000 4375) SIG_NAME M_J_CPU0_SA_DQ<12>
J 0
(-5990 4385);
DISPLAY 0.659574 (-5990 4385);
PAINT MONO (-5990 4385);
DISPLAY INVISIBLE (-5990 4385);
FORCEPROP 1 LASTPIN (-6000 4375) BN 12
J 0
(-6012 4383);
DISPLAY 0.489362 (-6012 4383);
PAINT GREEN (-6012 4383);
FORCEPROP 2 LAST CDS_LIB mstr_standard
J 0
(-5950 4375);
DISPLAY 0.723404 (-5950 4375);
PAINT MONO (-5950 4375);
DISPLAY INVISIBLE (-5950 4375);
FORCEPROP 1 LAST BODY_TYPE PLUMBING
J 0
(-5950 4425);
DISPLAY 0.872340 (-5950 4425);
PAINT GREEN (-5950 4425);
DISPLAY INVISIBLE (-5950 4425);
FORCEPROP 1 LAST HDL_TAP TRUE
J 0
(-5625 4250);
DISPLAY 0.872340 (-5625 4250);
DISPLAY INVISIBLE (-5625 4250);
FORCEPROP 1 LAST PATH I106
J 0
(-5952 4375);
DISPLAY 0.872340 (-5952 4375);
PAINT GREEN (-5952 4375);
DISPLAY INVISIBLE (-5952 4375);
FORCEADD TAP..1
(-5950 4425);
FORCEPROP 3 LASTPIN (-6000 4425) SIG_NAME M_J_CPU0_SA_DQ<13>
J 0
(-5990 4435);
DISPLAY 0.659574 (-5990 4435);
PAINT MONO (-5990 4435);
DISPLAY INVISIBLE (-5990 4435);
FORCEPROP 1 LASTPIN (-6000 4425) BN 13
J 0
(-6012 4433);
DISPLAY 0.489362 (-6012 4433);
PAINT GREEN (-6012 4433);
FORCEPROP 2 LAST CDS_LIB mstr_standard
J 0
(-5950 4425);
DISPLAY 0.723404 (-5950 4425);
PAINT MONO (-5950 4425);
DISPLAY INVISIBLE (-5950 4425);
FORCEPROP 1 LAST BODY_TYPE PLUMBING
J 0
(-5950 4475);
DISPLAY 0.872340 (-5950 4475);
PAINT GREEN (-5950 4475);
DISPLAY INVISIBLE (-5950 4475);
FORCEPROP 1 LAST HDL_TAP TRUE
J 0
(-5625 4300);
DISPLAY 0.872340 (-5625 4300);
DISPLAY INVISIBLE (-5625 4300);
FORCEPROP 1 LAST PATH I107
J 0
(-5952 4425);
DISPLAY 0.872340 (-5952 4425);
PAINT GREEN (-5952 4425);
DISPLAY INVISIBLE (-5952 4425);
FORCEADD TAP..1
(-5950 4475);
FORCEPROP 3 LASTPIN (-6000 4475) SIG_NAME M_J_CPU0_SA_DQ<14>
J 0
(-5990 4485);
DISPLAY 0.659574 (-5990 4485);
PAINT MONO (-5990 4485);
DISPLAY INVISIBLE (-5990 4485);
FORCEPROP 1 LASTPIN (-6000 4475) BN 14
J 0
(-6012 4483);
DISPLAY 0.489362 (-6012 4483);
PAINT GREEN (-6012 4483);
FORCEPROP 2 LAST CDS_LIB mstr_standard
J 0
(-5950 4475);
DISPLAY 0.723404 (-5950 4475);
PAINT MONO (-5950 4475);
DISPLAY INVISIBLE (-5950 4475);
FORCEPROP 1 LAST BODY_TYPE PLUMBING
J 0
(-5950 4525);
DISPLAY 0.872340 (-5950 4525);
PAINT GREEN (-5950 4525);
DISPLAY INVISIBLE (-5950 4525);
FORCEPROP 1 LAST HDL_TAP TRUE
J 0
(-5625 4350);
DISPLAY 0.872340 (-5625 4350);
DISPLAY INVISIBLE (-5625 4350);
FORCEPROP 1 LAST PATH I108
J 0
(-5952 4475);
DISPLAY 0.872340 (-5952 4475);
PAINT GREEN (-5952 4475);
DISPLAY INVISIBLE (-5952 4475);
FORCEADD TAP..1
(-5950 4525);
FORCEPROP 3 LASTPIN (-6000 4525) SIG_NAME M_J_CPU0_SA_DQ<15>
J 0
(-5990 4535);
DISPLAY 0.659574 (-5990 4535);
PAINT MONO (-5990 4535);
DISPLAY INVISIBLE (-5990 4535);
FORCEPROP 1 LASTPIN (-6000 4525) BN 15
J 0
(-6012 4533);
DISPLAY 0.489362 (-6012 4533);
PAINT GREEN (-6012 4533);
FORCEPROP 2 LAST CDS_LIB mstr_standard
J 0
(-5950 4525);
DISPLAY 0.723404 (-5950 4525);
PAINT MONO (-5950 4525);
DISPLAY INVISIBLE (-5950 4525);
FORCEPROP 1 LAST BODY_TYPE PLUMBING
J 0
(-5950 4575);
DISPLAY 0.872340 (-5950 4575);
PAINT GREEN (-5950 4575);
DISPLAY INVISIBLE (-5950 4575);
FORCEPROP 1 LAST HDL_TAP TRUE
J 0
(-5625 4400);
DISPLAY 0.872340 (-5625 4400);
DISPLAY INVISIBLE (-5625 4400);
FORCEPROP 1 LAST PATH I109
J 0
(-5952 4525);
DISPLAY 0.872340 (-5952 4525);
PAINT GREEN (-5952 4525);
DISPLAY INVISIBLE (-5952 4525);
FORCEADD OFFPAGE..6
(-8250 3975);
FORCEPROP 2 LAST $XR0 19 
J 0
(-8529 3975);
DISPLAY 0.638298 (-8529 3975);
PAINT MONO (-8529 3975);
FORCEPROP 2 LAST PATH I11
J 0
(-8200 4050);
DISPLAY 1.021277 (-8200 4050);
DISPLAY INVISIBLE (-8200 4050);
FORCEPROP 1 LAST COMMENT_BODY TRUE
J 0
(-8150 3900);
DISPLAY 0.872340 (-8150 3900);
PAINT GREEN (-8150 3900);
DISPLAY INVISIBLE (-8150 3900);
FORCEPROP 1 LAST OFFPAGE TRUE
J 0
(-7925 3850);
DISPLAY 0.872340 (-7925 3850);
PAINT GREEN (-7925 3850);
DISPLAY INVISIBLE (-7925 3850);
FORCEPROP 2 LAST CDS_LIB mstr_standard
J 0
(-8250 3975);
DISPLAY 0.723404 (-8250 3975);
PAINT MONO (-8250 3975);
DISPLAY INVISIBLE (-8250 3975);
FORCEADD TAP..1
(-5950 4625);
FORCEPROP 3 LASTPIN (-6000 4625) SIG_NAME M_J_CPU0_SA_DQ<17>
J 0
(-5990 4635);
DISPLAY 0.659574 (-5990 4635);
PAINT MONO (-5990 4635);
DISPLAY INVISIBLE (-5990 4635);
FORCEPROP 1 LASTPIN (-6000 4625) BN 17
J 0
(-6012 4633);
DISPLAY 0.489362 (-6012 4633);
PAINT GREEN (-6012 4633);
FORCEPROP 2 LAST CDS_LIB mstr_standard
J 0
(-5950 4625);
DISPLAY 0.723404 (-5950 4625);
PAINT MONO (-5950 4625);
DISPLAY INVISIBLE (-5950 4625);
FORCEPROP 1 LAST BODY_TYPE PLUMBING
J 0
(-5950 4675);
DISPLAY 0.872340 (-5950 4675);
PAINT GREEN (-5950 4675);
DISPLAY INVISIBLE (-5950 4675);
FORCEPROP 1 LAST HDL_TAP TRUE
J 0
(-5625 4500);
DISPLAY 0.872340 (-5625 4500);
DISPLAY INVISIBLE (-5625 4500);
FORCEPROP 1 LAST PATH I110
J 0
(-5952 4625);
DISPLAY 0.872340 (-5952 4625);
PAINT GREEN (-5952 4625);
DISPLAY INVISIBLE (-5952 4625);
FORCEADD TAP..1
(-5950 4575);
FORCEPROP 3 LASTPIN (-6000 4575) SIG_NAME M_J_CPU0_SA_DQ<16>
J 0
(-5990 4585);
DISPLAY 0.659574 (-5990 4585);
PAINT MONO (-5990 4585);
DISPLAY INVISIBLE (-5990 4585);
FORCEPROP 1 LASTPIN (-6000 4575) BN 16
J 0
(-6012 4583);
DISPLAY 0.489362 (-6012 4583);
PAINT GREEN (-6012 4583);
FORCEPROP 2 LAST CDS_LIB mstr_standard
J 0
(-5950 4575);
DISPLAY 0.723404 (-5950 4575);
PAINT MONO (-5950 4575);
DISPLAY INVISIBLE (-5950 4575);
FORCEPROP 1 LAST BODY_TYPE PLUMBING
J 0
(-5950 4625);
DISPLAY 0.872340 (-5950 4625);
PAINT GREEN (-5950 4625);
DISPLAY INVISIBLE (-5950 4625);
FORCEPROP 1 LAST HDL_TAP TRUE
J 0
(-5625 4450);
DISPLAY 0.872340 (-5625 4450);
DISPLAY INVISIBLE (-5625 4450);
FORCEPROP 1 LAST PATH I111
J 0
(-5952 4575);
DISPLAY 0.872340 (-5952 4575);
PAINT GREEN (-5952 4575);
DISPLAY INVISIBLE (-5952 4575);
FORCEADD TAP..1
(-5950 4775);
FORCEPROP 3 LASTPIN (-6000 4775) SIG_NAME M_J_CPU0_SA_DQ<20>
J 0
(-5990 4785);
DISPLAY 0.659574 (-5990 4785);
PAINT MONO (-5990 4785);
DISPLAY INVISIBLE (-5990 4785);
FORCEPROP 1 LASTPIN (-6000 4775) BN 20
J 0
(-6012 4783);
DISPLAY 0.489362 (-6012 4783);
PAINT GREEN (-6012 4783);
FORCEPROP 2 LAST CDS_LIB mstr_standard
J 0
(-5950 4775);
DISPLAY 0.723404 (-5950 4775);
PAINT MONO (-5950 4775);
DISPLAY INVISIBLE (-5950 4775);
FORCEPROP 1 LAST BODY_TYPE PLUMBING
J 0
(-5950 4825);
DISPLAY 0.872340 (-5950 4825);
PAINT GREEN (-5950 4825);
DISPLAY INVISIBLE (-5950 4825);
FORCEPROP 1 LAST HDL_TAP TRUE
J 0
(-5625 4650);
DISPLAY 0.872340 (-5625 4650);
DISPLAY INVISIBLE (-5625 4650);
FORCEPROP 1 LAST PATH I112
J 0
(-5952 4775);
DISPLAY 0.872340 (-5952 4775);
PAINT GREEN (-5952 4775);
DISPLAY INVISIBLE (-5952 4775);
FORCEADD TAP..1
(-5950 4725);
FORCEPROP 3 LASTPIN (-6000 4725) SIG_NAME M_J_CPU0_SA_DQ<19>
J 0
(-5990 4735);
DISPLAY 0.659574 (-5990 4735);
PAINT MONO (-5990 4735);
DISPLAY INVISIBLE (-5990 4735);
FORCEPROP 1 LASTPIN (-6000 4725) BN 19
J 0
(-6012 4733);
DISPLAY 0.489362 (-6012 4733);
PAINT GREEN (-6012 4733);
FORCEPROP 2 LAST CDS_LIB mstr_standard
J 0
(-5950 4725);
DISPLAY 0.723404 (-5950 4725);
PAINT MONO (-5950 4725);
DISPLAY INVISIBLE (-5950 4725);
FORCEPROP 1 LAST BODY_TYPE PLUMBING
J 0
(-5950 4775);
DISPLAY 0.872340 (-5950 4775);
PAINT GREEN (-5950 4775);
DISPLAY INVISIBLE (-5950 4775);
FORCEPROP 1 LAST HDL_TAP TRUE
J 0
(-5625 4600);
DISPLAY 0.872340 (-5625 4600);
DISPLAY INVISIBLE (-5625 4600);
FORCEPROP 1 LAST PATH I113
J 0
(-5952 4725);
DISPLAY 0.872340 (-5952 4725);
PAINT GREEN (-5952 4725);
DISPLAY INVISIBLE (-5952 4725);
FORCEADD TAP..1
(-5950 4675);
FORCEPROP 3 LASTPIN (-6000 4675) SIG_NAME M_J_CPU0_SA_DQ<18>
J 0
(-5990 4685);
DISPLAY 0.659574 (-5990 4685);
PAINT MONO (-5990 4685);
DISPLAY INVISIBLE (-5990 4685);
FORCEPROP 1 LASTPIN (-6000 4675) BN 18
J 0
(-6012 4683);
DISPLAY 0.489362 (-6012 4683);
PAINT GREEN (-6012 4683);
FORCEPROP 2 LAST CDS_LIB mstr_standard
J 0
(-5950 4675);
DISPLAY 0.723404 (-5950 4675);
PAINT MONO (-5950 4675);
DISPLAY INVISIBLE (-5950 4675);
FORCEPROP 1 LAST BODY_TYPE PLUMBING
J 0
(-5950 4725);
DISPLAY 0.872340 (-5950 4725);
PAINT GREEN (-5950 4725);
DISPLAY INVISIBLE (-5950 4725);
FORCEPROP 1 LAST HDL_TAP TRUE
J 0
(-5625 4550);
DISPLAY 0.872340 (-5625 4550);
DISPLAY INVISIBLE (-5625 4550);
FORCEPROP 1 LAST PATH I114
J 0
(-5952 4675);
DISPLAY 0.872340 (-5952 4675);
PAINT GREEN (-5952 4675);
DISPLAY INVISIBLE (-5952 4675);
FORCEADD TAP..1
(-5950 4875);
FORCEPROP 3 LASTPIN (-6000 4875) SIG_NAME M_J_CPU0_SA_DQ<22>
J 0
(-5990 4885);
DISPLAY 0.659574 (-5990 4885);
PAINT MONO (-5990 4885);
DISPLAY INVISIBLE (-5990 4885);
FORCEPROP 1 LASTPIN (-6000 4875) BN 22
J 0
(-6012 4883);
DISPLAY 0.489362 (-6012 4883);
PAINT GREEN (-6012 4883);
FORCEPROP 2 LAST CDS_LIB mstr_standard
J 0
(-5950 4875);
DISPLAY 0.723404 (-5950 4875);
PAINT MONO (-5950 4875);
DISPLAY INVISIBLE (-5950 4875);
FORCEPROP 1 LAST BODY_TYPE PLUMBING
J 0
(-5950 4925);
DISPLAY 0.872340 (-5950 4925);
PAINT GREEN (-5950 4925);
DISPLAY INVISIBLE (-5950 4925);
FORCEPROP 1 LAST HDL_TAP TRUE
J 0
(-5625 4750);
DISPLAY 0.872340 (-5625 4750);
DISPLAY INVISIBLE (-5625 4750);
FORCEPROP 1 LAST PATH I115
J 0
(-5952 4875);
DISPLAY 0.872340 (-5952 4875);
PAINT GREEN (-5952 4875);
DISPLAY INVISIBLE (-5952 4875);
FORCEADD TAP..1
(-5950 4825);
FORCEPROP 3 LASTPIN (-6000 4825) SIG_NAME M_J_CPU0_SA_DQ<21>
J 0
(-5990 4835);
DISPLAY 0.659574 (-5990 4835);
PAINT MONO (-5990 4835);
DISPLAY INVISIBLE (-5990 4835);
FORCEPROP 1 LASTPIN (-6000 4825) BN 21
J 0
(-6012 4833);
DISPLAY 0.489362 (-6012 4833);
PAINT GREEN (-6012 4833);
FORCEPROP 2 LAST CDS_LIB mstr_standard
J 0
(-5950 4825);
DISPLAY 0.723404 (-5950 4825);
PAINT MONO (-5950 4825);
DISPLAY INVISIBLE (-5950 4825);
FORCEPROP 1 LAST BODY_TYPE PLUMBING
J 0
(-5950 4875);
DISPLAY 0.872340 (-5950 4875);
PAINT GREEN (-5950 4875);
DISPLAY INVISIBLE (-5950 4875);
FORCEPROP 1 LAST HDL_TAP TRUE
J 0
(-5625 4700);
DISPLAY 0.872340 (-5625 4700);
DISPLAY INVISIBLE (-5625 4700);
FORCEPROP 1 LAST PATH I116
J 0
(-5952 4825);
DISPLAY 0.872340 (-5952 4825);
PAINT GREEN (-5952 4825);
DISPLAY INVISIBLE (-5952 4825);
FORCEADD TAP..1
(-5950 5025);
FORCEPROP 3 LASTPIN (-6000 5025) SIG_NAME M_J_CPU0_SA_DQ<25>
J 0
(-5990 5035);
DISPLAY 0.659574 (-5990 5035);
PAINT MONO (-5990 5035);
DISPLAY INVISIBLE (-5990 5035);
FORCEPROP 1 LASTPIN (-6000 5025) BN 25
J 0
(-6012 5033);
DISPLAY 0.489362 (-6012 5033);
PAINT GREEN (-6012 5033);
FORCEPROP 2 LAST CDS_LIB mstr_standard
J 0
(-5950 5025);
DISPLAY 0.723404 (-5950 5025);
PAINT MONO (-5950 5025);
DISPLAY INVISIBLE (-5950 5025);
FORCEPROP 1 LAST BODY_TYPE PLUMBING
J 0
(-5950 5075);
DISPLAY 0.872340 (-5950 5075);
PAINT GREEN (-5950 5075);
DISPLAY INVISIBLE (-5950 5075);
FORCEPROP 1 LAST HDL_TAP TRUE
J 0
(-5625 4900);
DISPLAY 0.872340 (-5625 4900);
DISPLAY INVISIBLE (-5625 4900);
FORCEPROP 1 LAST PATH I117
J 0
(-5952 5025);
DISPLAY 0.872340 (-5952 5025);
PAINT GREEN (-5952 5025);
DISPLAY INVISIBLE (-5952 5025);
FORCEADD TAP..1
(-5950 4975);
FORCEPROP 3 LASTPIN (-6000 4975) SIG_NAME M_J_CPU0_SA_DQ<24>
J 0
(-5990 4985);
DISPLAY 0.659574 (-5990 4985);
PAINT MONO (-5990 4985);
DISPLAY INVISIBLE (-5990 4985);
FORCEPROP 1 LASTPIN (-6000 4975) BN 24
J 0
(-6012 4983);
DISPLAY 0.489362 (-6012 4983);
PAINT GREEN (-6012 4983);
FORCEPROP 2 LAST CDS_LIB mstr_standard
J 0
(-5950 4975);
DISPLAY 0.723404 (-5950 4975);
PAINT MONO (-5950 4975);
DISPLAY INVISIBLE (-5950 4975);
FORCEPROP 1 LAST BODY_TYPE PLUMBING
J 0
(-5950 5025);
DISPLAY 0.872340 (-5950 5025);
PAINT GREEN (-5950 5025);
DISPLAY INVISIBLE (-5950 5025);
FORCEPROP 1 LAST HDL_TAP TRUE
J 0
(-5625 4850);
DISPLAY 0.872340 (-5625 4850);
DISPLAY INVISIBLE (-5625 4850);
FORCEPROP 1 LAST PATH I118
J 0
(-5952 4975);
DISPLAY 0.872340 (-5952 4975);
PAINT GREEN (-5952 4975);
DISPLAY INVISIBLE (-5952 4975);
FORCEADD TAP..1
(-5950 4925);
FORCEPROP 3 LASTPIN (-6000 4925) SIG_NAME M_J_CPU0_SA_DQ<23>
J 0
(-5990 4935);
DISPLAY 0.659574 (-5990 4935);
PAINT MONO (-5990 4935);
DISPLAY INVISIBLE (-5990 4935);
FORCEPROP 1 LASTPIN (-6000 4925) BN 23
J 0
(-6012 4933);
DISPLAY 0.489362 (-6012 4933);
PAINT GREEN (-6012 4933);
FORCEPROP 2 LAST CDS_LIB mstr_standard
J 0
(-5950 4925);
DISPLAY 0.723404 (-5950 4925);
PAINT MONO (-5950 4925);
DISPLAY INVISIBLE (-5950 4925);
FORCEPROP 1 LAST BODY_TYPE PLUMBING
J 0
(-5950 4975);
DISPLAY 0.872340 (-5950 4975);
PAINT GREEN (-5950 4975);
DISPLAY INVISIBLE (-5950 4975);
FORCEPROP 1 LAST HDL_TAP TRUE
J 0
(-5625 4800);
DISPLAY 0.872340 (-5625 4800);
DISPLAY INVISIBLE (-5625 4800);
FORCEPROP 1 LAST PATH I119
J 0
(-5952 4925);
DISPLAY 0.872340 (-5952 4925);
PAINT GREEN (-5952 4925);
DISPLAY INVISIBLE (-5952 4925);
FORCEADD OFFPAGE..1
(-8250 4025);
FORCEPROP 2 LAST $XR0 19 
J 0
(-8501 4025);
DISPLAY 0.638298 (-8501 4025);
PAINT MONO (-8501 4025);
FORCEPROP 2 LAST PATH I12
J 0
(-8200 4100);
DISPLAY 1.021277 (-8200 4100);
DISPLAY INVISIBLE (-8200 4100);
FORCEPROP 1 LAST COMMENT_BODY TRUE
J 0
(-8125 3925);
DISPLAY 0.872340 (-8125 3925);
PAINT GREEN (-8125 3925);
DISPLAY INVISIBLE (-8125 3925);
FORCEPROP 1 LAST OFFPAGE TRUE
J 0
(-7925 3900);
DISPLAY 0.872340 (-7925 3900);
PAINT GREEN (-7925 3900);
DISPLAY INVISIBLE (-7925 3900);
FORCEPROP 2 LAST CDS_LIB mstr_standard
J 0
(-8250 4025);
DISPLAY 0.808511 (-8250 4025);
DISPLAY INVISIBLE (-8250 4025);
FORCEADD TAP..1
(-5950 5125);
FORCEPROP 3 LASTPIN (-6000 5125) SIG_NAME M_J_CPU0_SA_DQ<27>
J 0
(-5990 5135);
DISPLAY 0.659574 (-5990 5135);
PAINT MONO (-5990 5135);
DISPLAY INVISIBLE (-5990 5135);
FORCEPROP 1 LASTPIN (-6000 5125) BN 27
J 0
(-6012 5133);
DISPLAY 0.489362 (-6012 5133);
PAINT GREEN (-6012 5133);
FORCEPROP 2 LAST CDS_LIB mstr_standard
J 0
(-5950 5125);
DISPLAY 0.723404 (-5950 5125);
PAINT MONO (-5950 5125);
DISPLAY INVISIBLE (-5950 5125);
FORCEPROP 1 LAST BODY_TYPE PLUMBING
J 0
(-5950 5175);
DISPLAY 0.872340 (-5950 5175);
PAINT GREEN (-5950 5175);
DISPLAY INVISIBLE (-5950 5175);
FORCEPROP 1 LAST HDL_TAP TRUE
J 0
(-5625 5000);
DISPLAY 0.872340 (-5625 5000);
DISPLAY INVISIBLE (-5625 5000);
FORCEPROP 1 LAST PATH I120
J 0
(-5952 5125);
DISPLAY 0.872340 (-5952 5125);
PAINT GREEN (-5952 5125);
DISPLAY INVISIBLE (-5952 5125);
FORCEADD TAP..1
(-5950 5175);
FORCEPROP 3 LASTPIN (-6000 5175) SIG_NAME M_J_CPU0_SA_DQ<28>
J 0
(-5990 5185);
DISPLAY 0.659574 (-5990 5185);
PAINT MONO (-5990 5185);
DISPLAY INVISIBLE (-5990 5185);
FORCEPROP 1 LASTPIN (-6000 5175) BN 28
J 0
(-6012 5183);
DISPLAY 0.489362 (-6012 5183);
PAINT GREEN (-6012 5183);
FORCEPROP 2 LAST CDS_LIB mstr_standard
J 0
(-5950 5175);
DISPLAY 0.723404 (-5950 5175);
PAINT MONO (-5950 5175);
DISPLAY INVISIBLE (-5950 5175);
FORCEPROP 1 LAST BODY_TYPE PLUMBING
J 0
(-5950 5225);
DISPLAY 0.872340 (-5950 5225);
PAINT GREEN (-5950 5225);
DISPLAY INVISIBLE (-5950 5225);
FORCEPROP 1 LAST HDL_TAP TRUE
J 0
(-5625 5050);
DISPLAY 0.872340 (-5625 5050);
DISPLAY INVISIBLE (-5625 5050);
FORCEPROP 1 LAST PATH I121
J 0
(-5952 5175);
DISPLAY 0.872340 (-5952 5175);
PAINT GREEN (-5952 5175);
DISPLAY INVISIBLE (-5952 5175);
FORCEADD TAP..1
(-5950 5075);
FORCEPROP 3 LASTPIN (-6000 5075) SIG_NAME M_J_CPU0_SA_DQ<26>
J 0
(-5990 5085);
DISPLAY 0.659574 (-5990 5085);
PAINT MONO (-5990 5085);
DISPLAY INVISIBLE (-5990 5085);
FORCEPROP 1 LASTPIN (-6000 5075) BN 26
J 0
(-6012 5083);
DISPLAY 0.489362 (-6012 5083);
PAINT GREEN (-6012 5083);
FORCEPROP 2 LAST CDS_LIB mstr_standard
J 0
(-5950 5075);
DISPLAY 0.723404 (-5950 5075);
PAINT MONO (-5950 5075);
DISPLAY INVISIBLE (-5950 5075);
FORCEPROP 1 LAST BODY_TYPE PLUMBING
J 0
(-5950 5125);
DISPLAY 0.872340 (-5950 5125);
PAINT GREEN (-5950 5125);
DISPLAY INVISIBLE (-5950 5125);
FORCEPROP 1 LAST HDL_TAP TRUE
J 0
(-5625 4950);
DISPLAY 0.872340 (-5625 4950);
DISPLAY INVISIBLE (-5625 4950);
FORCEPROP 1 LAST PATH I122
J 0
(-5952 5075);
DISPLAY 0.872340 (-5952 5075);
PAINT GREEN (-5952 5075);
DISPLAY INVISIBLE (-5952 5075);
FORCEADD TAP..1
(-5950 5275);
FORCEPROP 3 LASTPIN (-6000 5275) SIG_NAME M_J_CPU0_SA_DQ<30>
J 0
(-5990 5285);
DISPLAY 0.659574 (-5990 5285);
PAINT MONO (-5990 5285);
DISPLAY INVISIBLE (-5990 5285);
FORCEPROP 1 LASTPIN (-6000 5275) BN 30
J 0
(-6012 5283);
DISPLAY 0.489362 (-6012 5283);
PAINT GREEN (-6012 5283);
FORCEPROP 2 LAST CDS_LIB mstr_standard
J 0
(-5950 5275);
DISPLAY 0.723404 (-5950 5275);
PAINT MONO (-5950 5275);
DISPLAY INVISIBLE (-5950 5275);
FORCEPROP 1 LAST BODY_TYPE PLUMBING
J 0
(-5950 5325);
DISPLAY 0.872340 (-5950 5325);
PAINT GREEN (-5950 5325);
DISPLAY INVISIBLE (-5950 5325);
FORCEPROP 1 LAST HDL_TAP TRUE
J 0
(-5625 5150);
DISPLAY 0.872340 (-5625 5150);
DISPLAY INVISIBLE (-5625 5150);
FORCEPROP 1 LAST PATH I123
J 0
(-5952 5275);
DISPLAY 0.872340 (-5952 5275);
PAINT GREEN (-5952 5275);
DISPLAY INVISIBLE (-5952 5275);
FORCEADD TAP..1
(-5950 5225);
FORCEPROP 3 LASTPIN (-6000 5225) SIG_NAME M_J_CPU0_SA_DQ<29>
J 0
(-5990 5235);
DISPLAY 0.659574 (-5990 5235);
PAINT MONO (-5990 5235);
DISPLAY INVISIBLE (-5990 5235);
FORCEPROP 1 LASTPIN (-6000 5225) BN 29
J 0
(-6012 5233);
DISPLAY 0.489362 (-6012 5233);
PAINT GREEN (-6012 5233);
FORCEPROP 2 LAST CDS_LIB mstr_standard
J 0
(-5950 5225);
DISPLAY 0.723404 (-5950 5225);
PAINT MONO (-5950 5225);
DISPLAY INVISIBLE (-5950 5225);
FORCEPROP 1 LAST BODY_TYPE PLUMBING
J 0
(-5950 5275);
DISPLAY 0.872340 (-5950 5275);
PAINT GREEN (-5950 5275);
DISPLAY INVISIBLE (-5950 5275);
FORCEPROP 1 LAST HDL_TAP TRUE
J 0
(-5625 5100);
DISPLAY 0.872340 (-5625 5100);
DISPLAY INVISIBLE (-5625 5100);
FORCEPROP 1 LAST PATH I124
J 0
(-5952 5225);
DISPLAY 0.872340 (-5952 5225);
PAINT GREEN (-5952 5225);
DISPLAY INVISIBLE (-5952 5225);
FORCEADD TAP..1
(-5950 5325);
FORCEPROP 3 LASTPIN (-6000 5325) SIG_NAME M_J_CPU0_SA_DQ<31>
J 0
(-5990 5335);
DISPLAY 0.659574 (-5990 5335);
PAINT MONO (-5990 5335);
DISPLAY INVISIBLE (-5990 5335);
FORCEPROP 1 LASTPIN (-6000 5325) BN 31
J 0
(-6012 5333);
DISPLAY 0.489362 (-6012 5333);
PAINT GREEN (-6012 5333);
FORCEPROP 2 LAST CDS_LIB mstr_standard
J 0
(-5950 5325);
DISPLAY 0.723404 (-5950 5325);
PAINT MONO (-5950 5325);
DISPLAY INVISIBLE (-5950 5325);
FORCEPROP 1 LAST BODY_TYPE PLUMBING
J 0
(-5950 5375);
DISPLAY 0.872340 (-5950 5375);
PAINT GREEN (-5950 5375);
DISPLAY INVISIBLE (-5950 5375);
FORCEPROP 1 LAST HDL_TAP TRUE
J 0
(-5625 5200);
DISPLAY 0.872340 (-5625 5200);
DISPLAY INVISIBLE (-5625 5200);
FORCEPROP 1 LAST PATH I125
J 0
(-5952 5325);
DISPLAY 0.872340 (-5952 5325);
PAINT GREEN (-5952 5325);
DISPLAY INVISIBLE (-5952 5325);
FORCEADD OFFPAGE..3
(-5200 5375);
FORCEPROP 2 LAST $XR0 19 
J 0
(-4986 5375);
DISPLAY 0.638298 (-4986 5375);
PAINT MONO (-4986 5375);
FORCEPROP 2 LAST PATH I126
J 0
(-5000 5450);
DISPLAY 1.021277 (-5000 5450);
DISPLAY INVISIBLE (-5000 5450);
FORCEPROP 1 LAST COMMENT_BODY TRUE
J 0
(-5250 5275);
DISPLAY 0.872340 (-5250 5275);
PAINT GREEN (-5250 5275);
DISPLAY INVISIBLE (-5250 5275);
FORCEPROP 1 LAST OFFPAGE TRUE
J 0
(-4875 5250);
DISPLAY 0.872340 (-4875 5250);
PAINT GREEN (-4875 5250);
DISPLAY INVISIBLE (-4875 5250);
FORCEPROP 2 LAST CDS_LIB mstr_standard
J 0
(-5200 5375);
DISPLAY 0.723404 (-5200 5375);
PAINT MONO (-5200 5375);
DISPLAY INVISIBLE (-5200 5375);
FORCEADD OFFPAGE..5
(-7125 1350);
FORCEPROP 2 LAST $XR0 94 
J 0
(-7349 1350);
DISPLAY 0.638298 (-7349 1350);
PAINT MONO (-7349 1350);
FORCEPROP 2 LAST PATH I127
J 0
(-7375 1400);
DISPLAY 1.021277 (-7375 1400);
DISPLAY INVISIBLE (-7375 1400);
FORCEPROP 1 LAST COMMENT_BODY TRUE
J 0
(-7025 1275);
DISPLAY 0.872340 (-7025 1275);
PAINT GREEN (-7025 1275);
DISPLAY INVISIBLE (-7025 1275);
FORCEPROP 1 LAST OFFPAGE TRUE
J 0
(-6800 1225);
DISPLAY 0.872340 (-6800 1225);
PAINT GREEN (-6800 1225);
DISPLAY INVISIBLE (-6800 1225);
FORCEPROP 2 LAST BOM_COST MEM
J 0
(-7200 1425);
DISPLAY 0.808511 (-7200 1425);
DISPLAY INVISIBLE (-7200 1425);
FORCEPROP 2 LAST CDS_LIB mstr_standard
J 0
(-7125 1350);
DISPLAY 0.808511 (-7125 1350);
DISPLAY INVISIBLE (-7125 1350);
FORCEADD GND..1
(-6350 950);
FORCEPROP 3 LASTPIN (-6350 1000) SIG_NAME GND\g
J 0
(-6340 1010);
DISPLAY 0.659574 (-6340 1010);
PAINT MONO (-6340 1010);
DISPLAY INVISIBLE (-6340 1010);
FORCEPROP 1 LAST SIZE 1B
J 0
(-6275 900);
DISPLAY 0.851064 (-6275 900);
PAINT GREEN (-6275 900);
DISPLAY INVISIBLE (-6275 900);
FORCEPROP 2 LAST BOM_COST MEM
J 0
(-6450 1025);
DISPLAY 0.808511 (-6450 1025);
DISPLAY INVISIBLE (-6450 1025);
FORCEPROP 2 LAST CDS_LIB mstr_symbols
J 0
(-6350 950);
DISPLAY 0.808511 (-6350 950);
DISPLAY INVISIBLE (-6350 950);
FORCEPROP 1 LAST BODY_TYPE PLUMBING
J 0
(-6395 907);
DISPLAY 0.340426 (-6395 907);
PAINT GREEN (-6395 907);
DISPLAY INVISIBLE (-6395 907);
FORCEPROP 1 LAST PATH I128
J 0
(-6275 950);
DISPLAY 0.872340 (-6275 950);
PAINT AQUA (-6275 950);
DISPLAY INVISIBLE (-6275 950);
FORCEPROP 1 LAST VOLTAGE 0.0
J 0
(-6395 907);
DISPLAY 0.723404 (-6395 907);
PAINT SKYBLUE (-6395 907);
DISPLAY INVISIBLE (-6395 907);
FORCEPROP 1 LAST HDL_POWER GND
J 0
(-6350 1100);
DISPLAY 0.851064 (-6350 1100);
PAINT GREEN (-6350 1100);
DISPLAY INVISIBLE (-6350 1100);
FORCEADD Q_RES..2
(-6350 1175);
FORCEPROP 1 LAST LOCATION R767
J 0
(-6305 1300);
DISPLAY 0.489362 (-6305 1300);
PAINT SKYBLUE (-6305 1300);
FORCEPROP 0 LAST $SEC 1
J 0
(-6300 1350);
DISPLAY 0.680851 (-6300 1350);
PAINT MONO (-6300 1350);
DISPLAY INVISIBLE (-6300 1350);
FORCEPROP 0 LAST CDS_SEC 1
J 0
(-6300 1350);
DISPLAY 1.021277 (-6300 1350);
DISPLAY INVISIBLE (-6300 1350);
FORCEPROP 1 LASTPIN (-6350 1275) $PN 1
J 0
(-6345 1237);
DISPLAY 0.489362 (-6345 1237);
PAINT MONO (-6345 1237);
FORCEPROP 1 LASTPIN (-6350 1075) $PN 2
J 0
(-6345 1085);
DISPLAY 0.489362 (-6345 1085);
PAINT MONO (-6345 1085);
FORCEPROP 1 LAST WATTAGE 1/16W
J 0
(-6310 1150);
DISPLAY 0.489362 (-6310 1150);
PAINT SKYBLUE (-6310 1150);
FORCEPROP 1 LAST MATERIAL CHIP
J 0
(-6310 1100);
DISPLAY 0.489362 (-6310 1100);
PAINT SKYBLUE (-6310 1100);
FORCEPROP 1 LAST TOLERANCE 1%
J 0
(-6305 1200);
DISPLAY 0.489362 (-6305 1200);
PAINT SKYBLUE (-6305 1200);
FORCEPROP 1 LAST VALUE 35.7K
J 0
(-6305 1250);
DISPLAY 0.489362 (-6305 1250);
PAINT SKYBLUE (-6305 1250);
FORCEPROP 1 LAST PART_NUMBER CS33572FB01
J 0
(-6310 1050);
DISPLAY 0.489362 (-6310 1050);
PAINT SKYBLUE (-6310 1050);
FORCEPROP 1 LAST PACK_TYPE 0402LF
J 0
(-6310 1000);
DISPLAY 0.489362 (-6310 1000);
PAINT SKYBLUE (-6310 1000);
FORCEPROP 2 LAST CDS_LIB pure_quanta
J 0
(-6350 1175);
DISPLAY INVISIBLE (-6350 1175);
FORCEPROP 1 LAST PATH I129
J 0
(-6300 1350);
DISPLAY 0.978723 (-6300 1350);
PAINT WHITE (-6300 1350);
DISPLAY INVISIBLE (-6300 1350);
FORCEADD OFFPAGE..1
(-8250 4225);
FORCEPROP 2 LAST $XR0 19 
J 0
(-8501 4225);
DISPLAY 0.638298 (-8501 4225);
PAINT MONO (-8501 4225);
FORCEPROP 2 LAST PATH I13
J 0
(-8200 4300);
DISPLAY 1.021277 (-8200 4300);
DISPLAY INVISIBLE (-8200 4300);
FORCEPROP 1 LAST COMMENT_BODY TRUE
J 0
(-8125 4125);
DISPLAY 0.872340 (-8125 4125);
PAINT GREEN (-8125 4125);
DISPLAY INVISIBLE (-8125 4125);
FORCEPROP 1 LAST OFFPAGE TRUE
J 0
(-7925 4100);
DISPLAY 0.872340 (-7925 4100);
PAINT GREEN (-7925 4100);
DISPLAY INVISIBLE (-7925 4100);
FORCEPROP 2 LAST CDS_LIB mstr_standard
J 0
(-8250 4225);
DISPLAY 0.723404 (-8250 4225);
PAINT MONO (-8250 4225);
DISPLAY INVISIBLE (-8250 4225);
FORCEADD OFFPAGE..1
(-8250 4175);
FORCEPROP 2 LAST $XR0 19 
J 0
(-8501 4175);
DISPLAY 0.638298 (-8501 4175);
PAINT MONO (-8501 4175);
FORCEPROP 2 LAST PATH I14
J 0
(-8200 4250);
DISPLAY 1.021277 (-8200 4250);
DISPLAY INVISIBLE (-8200 4250);
FORCEPROP 1 LAST COMMENT_BODY TRUE
J 0
(-8125 4075);
DISPLAY 0.872340 (-8125 4075);
PAINT GREEN (-8125 4075);
DISPLAY INVISIBLE (-8125 4075);
FORCEPROP 1 LAST OFFPAGE TRUE
J 0
(-7925 4050);
DISPLAY 0.872340 (-7925 4050);
PAINT GREEN (-7925 4050);
DISPLAY INVISIBLE (-7925 4050);
FORCEPROP 2 LAST CDS_LIB mstr_standard
J 0
(-8250 4175);
DISPLAY 0.808511 (-8250 4175);
DISPLAY INVISIBLE (-8250 4175);
FORCEADD GND..1
(-2050 1850);
FORCEPROP 3 LASTPIN (-2050 1900) SIG_NAME GND\g
J 0
(-2040 1910);
DISPLAY 0.659574 (-2040 1910);
PAINT MONO (-2040 1910);
DISPLAY INVISIBLE (-2040 1910);
FORCEPROP 1 LAST SIZE 1B
J 0
(-1975 1800);
DISPLAY 0.851064 (-1975 1800);
PAINT GREEN (-1975 1800);
DISPLAY INVISIBLE (-1975 1800);
FORCEPROP 2 LAST CDS_LIB mstr_symbols
J 0
(-2050 1850);
DISPLAY 0.723404 (-2050 1850);
DISPLAY INVISIBLE (-2050 1850);
FORCEPROP 1 LAST BODY_TYPE PLUMBING
J 0
(-2095 1807);
DISPLAY 0.340426 (-2095 1807);
PAINT GREEN (-2095 1807);
DISPLAY INVISIBLE (-2095 1807);
FORCEPROP 1 LAST PATH I141
J 0
(-1975 1850);
DISPLAY 0.872340 (-1975 1850);
PAINT AQUA (-1975 1850);
DISPLAY INVISIBLE (-1975 1850);
FORCEPROP 1 LAST VOLTAGE 0.0
J 0
(-2095 1807);
DISPLAY 0.723404 (-2095 1807);
PAINT SKYBLUE (-2095 1807);
DISPLAY INVISIBLE (-2095 1807);
FORCEPROP 1 LAST HDL_POWER GND
J 0
(-2050 2000);
DISPLAY 0.851064 (-2050 2000);
PAINT GREEN (-2050 2000);
DISPLAY INVISIBLE (-2050 2000);
FORCEADD GND..1
(-250 1625);
FORCEPROP 3 LASTPIN (-250 1675) SIG_NAME GND\g
J 0
(-240 1685);
DISPLAY 0.659574 (-240 1685);
PAINT MONO (-240 1685);
DISPLAY INVISIBLE (-240 1685);
FORCEPROP 2 LAST CDS_LIB mstr_symbols
J 0
(-250 1625);
DISPLAY 0.723404 (-250 1625);
DISPLAY INVISIBLE (-250 1625);
FORCEPROP 1 LAST SIZE 1B
J 0
(-175 1575);
DISPLAY 0.851064 (-175 1575);
PAINT GREEN (-175 1575);
DISPLAY INVISIBLE (-175 1575);
FORCEPROP 1 LAST BODY_TYPE PLUMBING
J 0
(-295 1582);
DISPLAY 0.340426 (-295 1582);
PAINT GREEN (-295 1582);
DISPLAY INVISIBLE (-295 1582);
FORCEPROP 1 LAST PATH I142
J 0
(-175 1625);
DISPLAY 0.872340 (-175 1625);
PAINT AQUA (-175 1625);
DISPLAY INVISIBLE (-175 1625);
FORCEPROP 1 LAST VOLTAGE 0.0
J 0
(-295 1582);
DISPLAY 0.723404 (-295 1582);
PAINT SKYBLUE (-295 1582);
DISPLAY INVISIBLE (-295 1582);
FORCEPROP 1 LAST HDL_POWER GND
J 0
(-250 1775);
DISPLAY 0.851064 (-250 1775);
PAINT GREEN (-250 1775);
DISPLAY INVISIBLE (-250 1775);
FORCEADD OFFPAGE..1
(-8250 4075);
FORCEPROP 2 LAST $XR0 19 
J 0
(-8501 4075);
DISPLAY 0.638298 (-8501 4075);
PAINT MONO (-8501 4075);
FORCEPROP 2 LAST PATH I15
J 0
(-8200 4150);
DISPLAY 1.021277 (-8200 4150);
DISPLAY INVISIBLE (-8200 4150);
FORCEPROP 1 LAST COMMENT_BODY TRUE
J 0
(-8125 3975);
DISPLAY 0.872340 (-8125 3975);
PAINT GREEN (-8125 3975);
DISPLAY INVISIBLE (-8125 3975);
FORCEPROP 1 LAST OFFPAGE TRUE
J 0
(-7925 3950);
DISPLAY 0.872340 (-7925 3950);
PAINT GREEN (-7925 3950);
DISPLAY INVISIBLE (-7925 3950);
FORCEPROP 2 LAST CDS_LIB mstr_standard
J 0
(-8250 4075);
DISPLAY 0.723404 (-8250 4075);
PAINT MONO (-8250 4075);
DISPLAY INVISIBLE (-8250 4075);
FORCEADD OFFPAGE..1
(-8250 4525);
FORCEPROP 2 LAST $XR0 19 
J 0
(-8501 4525);
DISPLAY 0.638298 (-8501 4525);
PAINT MONO (-8501 4525);
FORCEPROP 2 LAST PATH I16
J 0
(-8200 4600);
DISPLAY 1.021277 (-8200 4600);
DISPLAY INVISIBLE (-8200 4600);
FORCEPROP 1 LAST COMMENT_BODY TRUE
J 0
(-8125 4425);
DISPLAY 0.872340 (-8125 4425);
PAINT GREEN (-8125 4425);
DISPLAY INVISIBLE (-8125 4425);
FORCEPROP 1 LAST OFFPAGE TRUE
J 0
(-7925 4400);
DISPLAY 0.872340 (-7925 4400);
PAINT GREEN (-7925 4400);
DISPLAY INVISIBLE (-7925 4400);
FORCEPROP 2 LAST CDS_LIB mstr_standard
J 0
(-8250 4525);
DISPLAY 0.723404 (-8250 4525);
PAINT MONO (-8250 4525);
DISPLAY INVISIBLE (-8250 4525);
FORCEADD OFFPAGE..1
(-8250 4375);
FORCEPROP 2 LAST $XR0 19 
J 0
(-8501 4375);
DISPLAY 0.638298 (-8501 4375);
PAINT MONO (-8501 4375);
FORCEPROP 2 LAST PATH I17
J 0
(-8200 4450);
DISPLAY 1.021277 (-8200 4450);
DISPLAY INVISIBLE (-8200 4450);
FORCEPROP 1 LAST COMMENT_BODY TRUE
J 0
(-8125 4275);
DISPLAY 0.872340 (-8125 4275);
PAINT GREEN (-8125 4275);
DISPLAY INVISIBLE (-8125 4275);
FORCEPROP 1 LAST OFFPAGE TRUE
J 0
(-7925 4250);
DISPLAY 0.872340 (-7925 4250);
PAINT GREEN (-7925 4250);
DISPLAY INVISIBLE (-7925 4250);
FORCEPROP 2 LAST CDS_LIB mstr_standard
J 0
(-8250 4375);
DISPLAY 0.723404 (-8250 4375);
PAINT MONO (-8250 4375);
DISPLAY INVISIBLE (-8250 4375);
FORCEADD SCONN288_DDR506112002KQ..3
(-1150 3625);
FORCEPROP 1 LAST LOCATION J68
J 0
(-1600 5600);
DISPLAY 0.468085 (-1600 5600);
PAINT SKYBLUE (-1600 5600);
FORCEPROP 0 LAST $SEC 3
J 0
(-1600 5750);
DISPLAY 0.680851 (-1600 5750);
PAINT MONO (-1600 5750);
DISPLAY INVISIBLE (-1600 5750);
FORCEPROP 2 LAST CDS_SEC 3
J 0
(-1600 5750);
DISPLAY 1.021277 (-1600 5750);
DISPLAY INVISIBLE (-1600 5750);
FORCEPROP 0 LASTPIN (-550 2025) $PN G1
J 0
(-540 2035);
DISPLAY 0.680851 (-540 2035);
PAINT MONO (-540 2035);
FORCEPROP 0 LASTPIN (-550 1975) $PN G2
J 0
(-540 1985);
DISPLAY 0.680851 (-540 1985);
PAINT MONO (-540 1985);
FORCEPROP 0 LASTPIN (-550 1925) $PN G3
J 0
(-540 1935);
DISPLAY 0.680851 (-540 1935);
PAINT MONO (-540 1935);
FORCEPROP 0 LASTPIN (-1750 5175) $PN 1
J 2
(-1760 5185);
DISPLAY 0.680851 (-1760 5185);
PAINT MONO (-1760 5185);
FORCEPROP 0 LASTPIN (-1750 5225) $PN 145
J 2
(-1760 5235);
DISPLAY 0.680851 (-1760 5235);
PAINT MONO (-1760 5235);
FORCEPROP 0 LASTPIN (-1750 5275) $PN 146
J 2
(-1760 5285);
DISPLAY 0.680851 (-1760 5285);
PAINT MONO (-1760 5285);
FORCEPROP 0 LASTPIN (-550 2125) $PN 6
J 0
(-540 2135);
DISPLAY 0.680851 (-540 2135);
PAINT MONO (-540 2135);
FORCEPROP 0 LASTPIN (-550 2175) $PN 8
J 0
(-540 2185);
DISPLAY 0.680851 (-540 2185);
PAINT MONO (-540 2185);
FORCEPROP 0 LASTPIN (-550 2225) $PN 10
J 0
(-540 2235);
DISPLAY 0.680851 (-540 2235);
PAINT MONO (-540 2235);
FORCEPROP 0 LASTPIN (-550 2275) $PN 13
J 0
(-540 2285);
DISPLAY 0.680851 (-540 2285);
PAINT MONO (-540 2285);
FORCEPROP 0 LASTPIN (-550 2325) $PN 15
J 0
(-540 2335);
DISPLAY 0.680851 (-540 2335);
PAINT MONO (-540 2335);
FORCEPROP 0 LASTPIN (-550 2375) $PN 17
J 0
(-540 2385);
DISPLAY 0.680851 (-540 2385);
PAINT MONO (-540 2385);
FORCEPROP 0 LASTPIN (-550 2425) $PN 19
J 0
(-540 2435);
DISPLAY 0.680851 (-540 2435);
PAINT MONO (-540 2435);
FORCEPROP 0 LASTPIN (-550 2475) $PN 21
J 0
(-540 2485);
DISPLAY 0.680851 (-540 2485);
PAINT MONO (-540 2485);
FORCEPROP 0 LASTPIN (-550 2525) $PN 24
J 0
(-540 2535);
DISPLAY 0.680851 (-540 2535);
PAINT MONO (-540 2535);
FORCEPROP 0 LASTPIN (-550 2575) $PN 26
J 0
(-540 2585);
DISPLAY 0.680851 (-540 2585);
PAINT MONO (-540 2585);
FORCEPROP 0 LASTPIN (-550 2625) $PN 28
J 0
(-540 2635);
DISPLAY 0.680851 (-540 2635);
PAINT MONO (-540 2635);
FORCEPROP 0 LASTPIN (-550 2675) $PN 30
J 0
(-540 2685);
DISPLAY 0.680851 (-540 2685);
PAINT MONO (-540 2685);
FORCEPROP 0 LASTPIN (-550 2725) $PN 32
J 0
(-540 2735);
DISPLAY 0.680851 (-540 2735);
PAINT MONO (-540 2735);
FORCEPROP 0 LASTPIN (-550 2775) $PN 35
J 0
(-540 2785);
DISPLAY 0.680851 (-540 2785);
PAINT MONO (-540 2785);
FORCEPROP 0 LASTPIN (-550 2825) $PN 37
J 0
(-540 2835);
DISPLAY 0.680851 (-540 2835);
PAINT MONO (-540 2835);
FORCEPROP 0 LASTPIN (-550 2875) $PN 39
J 0
(-540 2885);
DISPLAY 0.680851 (-540 2885);
PAINT MONO (-540 2885);
FORCEPROP 0 LASTPIN (-550 2925) $PN 41
J 0
(-540 2935);
DISPLAY 0.680851 (-540 2935);
PAINT MONO (-540 2935);
FORCEPROP 0 LASTPIN (-550 2975) $PN 43
J 0
(-540 2985);
DISPLAY 0.680851 (-540 2985);
PAINT MONO (-540 2985);
FORCEPROP 0 LASTPIN (-550 3025) $PN 46
J 0
(-540 3035);
DISPLAY 0.680851 (-540 3035);
PAINT MONO (-540 3035);
FORCEPROP 0 LASTPIN (-550 3075) $PN 48
J 0
(-540 3085);
DISPLAY 0.680851 (-540 3085);
PAINT MONO (-540 3085);
FORCEPROP 0 LASTPIN (-550 3125) $PN 50
J 0
(-540 3135);
DISPLAY 0.680851 (-540 3135);
PAINT MONO (-540 3135);
FORCEPROP 0 LASTPIN (-550 3175) $PN 52
J 0
(-540 3185);
DISPLAY 0.680851 (-540 3185);
PAINT MONO (-540 3185);
FORCEPROP 0 LASTPIN (-550 3225) $PN 54
J 0
(-540 3235);
DISPLAY 0.680851 (-540 3235);
PAINT MONO (-540 3235);
FORCEPROP 0 LASTPIN (-550 3275) $PN 57
J 0
(-540 3285);
DISPLAY 0.680851 (-540 3285);
PAINT MONO (-540 3285);
FORCEPROP 0 LASTPIN (-550 3325) $PN 59
J 0
(-540 3335);
DISPLAY 0.680851 (-540 3335);
PAINT MONO (-540 3335);
FORCEPROP 0 LASTPIN (-550 3375) $PN 61
J 0
(-540 3385);
DISPLAY 0.680851 (-540 3385);
PAINT MONO (-540 3385);
FORCEPROP 0 LASTPIN (-550 3425) $PN 63
J 0
(-540 3435);
DISPLAY 0.680851 (-540 3435);
PAINT MONO (-540 3435);
FORCEPROP 0 LASTPIN (-550 3475) $PN 65
J 0
(-540 3485);
DISPLAY 0.680851 (-540 3485);
PAINT MONO (-540 3485);
FORCEPROP 0 LASTPIN (-550 3525) $PN 67
J 0
(-540 3535);
DISPLAY 0.680851 (-540 3535);
PAINT MONO (-540 3535);
FORCEPROP 0 LASTPIN (-550 3575) $PN 69
J 0
(-540 3585);
DISPLAY 0.680851 (-540 3585);
PAINT MONO (-540 3585);
FORCEPROP 0 LASTPIN (-550 3625) $PN 71
J 0
(-540 3635);
DISPLAY 0.680851 (-540 3635);
PAINT MONO (-540 3635);
FORCEPROP 0 LASTPIN (-550 3675) $PN 73
J 0
(-540 3685);
DISPLAY 0.680851 (-540 3685);
PAINT MONO (-540 3685);
FORCEPROP 0 LASTPIN (-550 3725) $PN 75
J 0
(-540 3735);
DISPLAY 0.680851 (-540 3735);
PAINT MONO (-540 3735);
FORCEPROP 0 LASTPIN (-550 3775) $PN 77
J 0
(-540 3785);
DISPLAY 0.680851 (-540 3785);
PAINT MONO (-540 3785);
FORCEPROP 0 LASTPIN (-550 3825) $PN 79
J 0
(-540 3835);
DISPLAY 0.680851 (-540 3835);
PAINT MONO (-540 3835);
FORCEPROP 0 LASTPIN (-550 3875) $PN 81
J 0
(-540 3885);
DISPLAY 0.680851 (-540 3885);
PAINT MONO (-540 3885);
FORCEPROP 0 LASTPIN (-550 3925) $PN 83
J 0
(-540 3935);
DISPLAY 0.680851 (-540 3935);
PAINT MONO (-540 3935);
FORCEPROP 0 LASTPIN (-550 3975) $PN 85
J 0
(-540 3985);
DISPLAY 0.680851 (-540 3985);
PAINT MONO (-540 3985);
FORCEPROP 0 LASTPIN (-550 4025) $PN 88
J 0
(-540 4035);
DISPLAY 0.680851 (-540 4035);
PAINT MONO (-540 4035);
FORCEPROP 0 LASTPIN (-550 4075) $PN 90
J 0
(-540 4085);
DISPLAY 0.680851 (-540 4085);
PAINT MONO (-540 4085);
FORCEPROP 0 LASTPIN (-550 4125) $PN 92
J 0
(-540 4135);
DISPLAY 0.680851 (-540 4135);
PAINT MONO (-540 4135);
FORCEPROP 0 LASTPIN (-550 4175) $PN 95
J 0
(-540 4185);
DISPLAY 0.680851 (-540 4185);
PAINT MONO (-540 4185);
FORCEPROP 0 LASTPIN (-550 4225) $PN 97
J 0
(-540 4235);
DISPLAY 0.680851 (-540 4235);
PAINT MONO (-540 4235);
FORCEPROP 0 LASTPIN (-550 4275) $PN 99
J 0
(-540 4285);
DISPLAY 0.680851 (-540 4285);
PAINT MONO (-540 4285);
FORCEPROP 0 LASTPIN (-550 4325) $PN 101
J 0
(-540 4335);
DISPLAY 0.680851 (-540 4335);
PAINT MONO (-540 4335);
FORCEPROP 0 LASTPIN (-550 4375) $PN 103
J 0
(-540 4385);
DISPLAY 0.680851 (-540 4385);
PAINT MONO (-540 4385);
FORCEPROP 0 LASTPIN (-550 4425) $PN 106
J 0
(-540 4435);
DISPLAY 0.680851 (-540 4435);
PAINT MONO (-540 4435);
FORCEPROP 0 LASTPIN (-550 4475) $PN 108
J 0
(-540 4485);
DISPLAY 0.680851 (-540 4485);
PAINT MONO (-540 4485);
FORCEPROP 0 LASTPIN (-550 4525) $PN 110
J 0
(-540 4535);
DISPLAY 0.680851 (-540 4535);
PAINT MONO (-540 4535);
FORCEPROP 0 LASTPIN (-550 4575) $PN 112
J 0
(-540 4585);
DISPLAY 0.680851 (-540 4585);
PAINT MONO (-540 4585);
FORCEPROP 0 LASTPIN (-550 4625) $PN 114
J 0
(-540 4635);
DISPLAY 0.680851 (-540 4635);
PAINT MONO (-540 4635);
FORCEPROP 0 LASTPIN (-550 4675) $PN 117
J 0
(-540 4685);
DISPLAY 0.680851 (-540 4685);
PAINT MONO (-540 4685);
FORCEPROP 0 LASTPIN (-550 4725) $PN 119
J 0
(-540 4735);
DISPLAY 0.680851 (-540 4735);
PAINT MONO (-540 4735);
FORCEPROP 0 LASTPIN (-550 4775) $PN 121
J 0
(-540 4785);
DISPLAY 0.680851 (-540 4785);
PAINT MONO (-540 4785);
FORCEPROP 0 LASTPIN (-550 4825) $PN 123
J 0
(-540 4835);
DISPLAY 0.680851 (-540 4835);
PAINT MONO (-540 4835);
FORCEPROP 0 LASTPIN (-550 4875) $PN 125
J 0
(-540 4885);
DISPLAY 0.680851 (-540 4885);
PAINT MONO (-540 4885);
FORCEPROP 0 LASTPIN (-550 4925) $PN 128
J 0
(-540 4935);
DISPLAY 0.680851 (-540 4935);
PAINT MONO (-540 4935);
FORCEPROP 0 LASTPIN (-550 4975) $PN 130
J 0
(-540 4985);
DISPLAY 0.680851 (-540 4985);
PAINT MONO (-540 4985);
FORCEPROP 0 LASTPIN (-550 5025) $PN 132
J 0
(-540 5035);
DISPLAY 0.680851 (-540 5035);
PAINT MONO (-540 5035);
FORCEPROP 0 LASTPIN (-550 5075) $PN 134
J 0
(-540 5085);
DISPLAY 0.680851 (-540 5085);
PAINT MONO (-540 5085);
FORCEPROP 0 LASTPIN (-550 5125) $PN 136
J 0
(-540 5135);
DISPLAY 0.680851 (-540 5135);
PAINT MONO (-540 5135);
FORCEPROP 0 LASTPIN (-550 5175) $PN 139
J 0
(-540 5185);
DISPLAY 0.680851 (-540 5185);
PAINT MONO (-540 5185);
FORCEPROP 0 LASTPIN (-550 5225) $PN 141
J 0
(-540 5235);
DISPLAY 0.680851 (-540 5235);
PAINT MONO (-540 5235);
FORCEPROP 0 LASTPIN (-550 5275) $PN 143
J 0
(-540 5285);
DISPLAY 0.680851 (-540 5285);
PAINT MONO (-540 5285);
FORCEPROP 0 LASTPIN (-1750 2025) $PN 151
J 2
(-1760 2035);
DISPLAY 0.680851 (-1760 2035);
PAINT MONO (-1760 2035);
FORCEPROP 0 LASTPIN (-1750 2075) $PN 153
J 2
(-1760 2085);
DISPLAY 0.680851 (-1760 2085);
PAINT MONO (-1760 2085);
FORCEPROP 0 LASTPIN (-1750 2125) $PN 155
J 2
(-1760 2135);
DISPLAY 0.680851 (-1760 2135);
PAINT MONO (-1760 2135);
FORCEPROP 0 LASTPIN (-1750 2175) $PN 158
J 2
(-1760 2185);
DISPLAY 0.680851 (-1760 2185);
PAINT MONO (-1760 2185);
FORCEPROP 0 LASTPIN (-1750 2225) $PN 160
J 2
(-1760 2235);
DISPLAY 0.680851 (-1760 2235);
PAINT MONO (-1760 2235);
FORCEPROP 0 LASTPIN (-1750 2275) $PN 162
J 2
(-1760 2285);
DISPLAY 0.680851 (-1760 2285);
PAINT MONO (-1760 2285);
FORCEPROP 0 LASTPIN (-1750 2325) $PN 164
J 2
(-1760 2335);
DISPLAY 0.680851 (-1760 2335);
PAINT MONO (-1760 2335);
FORCEPROP 0 LASTPIN (-1750 2375) $PN 166
J 2
(-1760 2385);
DISPLAY 0.680851 (-1760 2385);
PAINT MONO (-1760 2385);
FORCEPROP 0 LASTPIN (-1750 2425) $PN 169
J 2
(-1760 2435);
DISPLAY 0.680851 (-1760 2435);
PAINT MONO (-1760 2435);
FORCEPROP 0 LASTPIN (-1750 2475) $PN 171
J 2
(-1760 2485);
DISPLAY 0.680851 (-1760 2485);
PAINT MONO (-1760 2485);
FORCEPROP 0 LASTPIN (-1750 2525) $PN 173
J 2
(-1760 2535);
DISPLAY 0.680851 (-1760 2535);
PAINT MONO (-1760 2535);
FORCEPROP 0 LASTPIN (-1750 2575) $PN 175
J 2
(-1760 2585);
DISPLAY 0.680851 (-1760 2585);
PAINT MONO (-1760 2585);
FORCEPROP 0 LASTPIN (-1750 2625) $PN 177
J 2
(-1760 2635);
DISPLAY 0.680851 (-1760 2635);
PAINT MONO (-1760 2635);
FORCEPROP 0 LASTPIN (-1750 2675) $PN 180
J 2
(-1760 2685);
DISPLAY 0.680851 (-1760 2685);
PAINT MONO (-1760 2685);
FORCEPROP 0 LASTPIN (-1750 2725) $PN 182
J 2
(-1760 2735);
DISPLAY 0.680851 (-1760 2735);
PAINT MONO (-1760 2735);
FORCEPROP 0 LASTPIN (-1750 2775) $PN 184
J 2
(-1760 2785);
DISPLAY 0.680851 (-1760 2785);
PAINT MONO (-1760 2785);
FORCEPROP 0 LASTPIN (-1750 2825) $PN 186
J 2
(-1760 2835);
DISPLAY 0.680851 (-1760 2835);
PAINT MONO (-1760 2835);
FORCEPROP 0 LASTPIN (-1750 2875) $PN 188
J 2
(-1760 2885);
DISPLAY 0.680851 (-1760 2885);
PAINT MONO (-1760 2885);
FORCEPROP 0 LASTPIN (-1750 2925) $PN 191
J 2
(-1760 2935);
DISPLAY 0.680851 (-1760 2935);
PAINT MONO (-1760 2935);
FORCEPROP 0 LASTPIN (-1750 2975) $PN 193
J 2
(-1760 2985);
DISPLAY 0.680851 (-1760 2985);
PAINT MONO (-1760 2985);
FORCEPROP 0 LASTPIN (-1750 3025) $PN 195
J 2
(-1760 3035);
DISPLAY 0.680851 (-1760 3035);
PAINT MONO (-1760 3035);
FORCEPROP 0 LASTPIN (-1750 3075) $PN 197
J 2
(-1760 3085);
DISPLAY 0.680851 (-1760 3085);
PAINT MONO (-1760 3085);
FORCEPROP 0 LASTPIN (-1750 3125) $PN 199
J 2
(-1760 3135);
DISPLAY 0.680851 (-1760 3135);
PAINT MONO (-1760 3135);
FORCEPROP 0 LASTPIN (-1750 3175) $PN 202
J 2
(-1760 3185);
DISPLAY 0.680851 (-1760 3185);
PAINT MONO (-1760 3185);
FORCEPROP 0 LASTPIN (-1750 3225) $PN 204
J 2
(-1760 3235);
DISPLAY 0.680851 (-1760 3235);
PAINT MONO (-1760 3235);
FORCEPROP 0 LASTPIN (-1750 3275) $PN 206
J 2
(-1760 3285);
DISPLAY 0.680851 (-1760 3285);
PAINT MONO (-1760 3285);
FORCEPROP 0 LASTPIN (-1750 3325) $PN 208
J 2
(-1760 3335);
DISPLAY 0.680851 (-1760 3335);
PAINT MONO (-1760 3335);
FORCEPROP 0 LASTPIN (-1750 3375) $PN 210
J 2
(-1760 3385);
DISPLAY 0.680851 (-1760 3385);
PAINT MONO (-1760 3385);
FORCEPROP 0 LASTPIN (-1750 3425) $PN 212
J 2
(-1760 3435);
DISPLAY 0.680851 (-1760 3435);
PAINT MONO (-1760 3435);
FORCEPROP 0 LASTPIN (-1750 3475) $PN 214
J 2
(-1760 3485);
DISPLAY 0.680851 (-1760 3485);
PAINT MONO (-1760 3485);
FORCEPROP 0 LASTPIN (-1750 3525) $PN 216
J 2
(-1760 3535);
DISPLAY 0.680851 (-1760 3535);
PAINT MONO (-1760 3535);
FORCEPROP 0 LASTPIN (-1750 3575) $PN 219
J 2
(-1760 3585);
DISPLAY 0.680851 (-1760 3585);
PAINT MONO (-1760 3585);
FORCEPROP 0 LASTPIN (-1750 3625) $PN 222
J 2
(-1760 3635);
DISPLAY 0.680851 (-1760 3635);
PAINT MONO (-1760 3635);
FORCEPROP 0 LASTPIN (-1750 3675) $PN 224
J 2
(-1760 3685);
DISPLAY 0.680851 (-1760 3685);
PAINT MONO (-1760 3685);
FORCEPROP 0 LASTPIN (-1750 3725) $PN 226
J 2
(-1760 3735);
DISPLAY 0.680851 (-1760 3735);
PAINT MONO (-1760 3735);
FORCEPROP 0 LASTPIN (-1750 3775) $PN 228
J 2
(-1760 3785);
DISPLAY 0.680851 (-1760 3785);
PAINT MONO (-1760 3785);
FORCEPROP 0 LASTPIN (-1750 3825) $PN 230
J 2
(-1760 3835);
DISPLAY 0.680851 (-1760 3835);
PAINT MONO (-1760 3835);
FORCEPROP 0 LASTPIN (-1750 3875) $PN 233
J 2
(-1760 3885);
DISPLAY 0.680851 (-1760 3885);
PAINT MONO (-1760 3885);
FORCEPROP 0 LASTPIN (-1750 3925) $PN 235
J 2
(-1760 3935);
DISPLAY 0.680851 (-1760 3935);
PAINT MONO (-1760 3935);
FORCEPROP 0 LASTPIN (-1750 3975) $PN 237
J 2
(-1760 3985);
DISPLAY 0.680851 (-1760 3985);
PAINT MONO (-1760 3985);
FORCEPROP 0 LASTPIN (-1750 4025) $PN 240
J 2
(-1760 4035);
DISPLAY 0.680851 (-1760 4035);
PAINT MONO (-1760 4035);
FORCEPROP 0 LASTPIN (-1750 4075) $PN 242
J 2
(-1760 4085);
DISPLAY 0.680851 (-1760 4085);
PAINT MONO (-1760 4085);
FORCEPROP 0 LASTPIN (-1750 4125) $PN 244
J 2
(-1760 4135);
DISPLAY 0.680851 (-1760 4135);
PAINT MONO (-1760 4135);
FORCEPROP 0 LASTPIN (-1750 4175) $PN 246
J 2
(-1760 4185);
DISPLAY 0.680851 (-1760 4185);
PAINT MONO (-1760 4185);
FORCEPROP 0 LASTPIN (-1750 4225) $PN 248
J 2
(-1760 4235);
DISPLAY 0.680851 (-1760 4235);
PAINT MONO (-1760 4235);
FORCEPROP 0 LASTPIN (-1750 4275) $PN 251
J 2
(-1760 4285);
DISPLAY 0.680851 (-1760 4285);
PAINT MONO (-1760 4285);
FORCEPROP 0 LASTPIN (-1750 4325) $PN 253
J 2
(-1760 4335);
DISPLAY 0.680851 (-1760 4335);
PAINT MONO (-1760 4335);
FORCEPROP 0 LASTPIN (-1750 4375) $PN 255
J 2
(-1760 4385);
DISPLAY 0.680851 (-1760 4385);
PAINT MONO (-1760 4385);
FORCEPROP 0 LASTPIN (-1750 4425) $PN 257
J 2
(-1760 4435);
DISPLAY 0.680851 (-1760 4435);
PAINT MONO (-1760 4435);
FORCEPROP 0 LASTPIN (-1750 4475) $PN 259
J 2
(-1760 4485);
DISPLAY 0.680851 (-1760 4485);
PAINT MONO (-1760 4485);
FORCEPROP 0 LASTPIN (-1750 4525) $PN 262
J 2
(-1760 4535);
DISPLAY 0.680851 (-1760 4535);
PAINT MONO (-1760 4535);
FORCEPROP 0 LASTPIN (-1750 4575) $PN 264
J 2
(-1760 4585);
DISPLAY 0.680851 (-1760 4585);
PAINT MONO (-1760 4585);
FORCEPROP 0 LASTPIN (-1750 4625) $PN 266
J 2
(-1760 4635);
DISPLAY 0.680851 (-1760 4635);
PAINT MONO (-1760 4635);
FORCEPROP 0 LASTPIN (-1750 4675) $PN 268
J 2
(-1760 4685);
DISPLAY 0.680851 (-1760 4685);
PAINT MONO (-1760 4685);
FORCEPROP 0 LASTPIN (-1750 4725) $PN 270
J 2
(-1760 4735);
DISPLAY 0.680851 (-1760 4735);
PAINT MONO (-1760 4735);
FORCEPROP 0 LASTPIN (-1750 4775) $PN 273
J 2
(-1760 4785);
DISPLAY 0.680851 (-1760 4785);
PAINT MONO (-1760 4785);
FORCEPROP 0 LASTPIN (-1750 4825) $PN 275
J 2
(-1760 4835);
DISPLAY 0.680851 (-1760 4835);
PAINT MONO (-1760 4835);
FORCEPROP 0 LASTPIN (-1750 4875) $PN 277
J 2
(-1760 4885);
DISPLAY 0.680851 (-1760 4885);
PAINT MONO (-1760 4885);
FORCEPROP 0 LASTPIN (-1750 4925) $PN 279
J 2
(-1760 4935);
DISPLAY 0.680851 (-1760 4935);
PAINT MONO (-1760 4935);
FORCEPROP 0 LASTPIN (-1750 4975) $PN 281
J 2
(-1760 4985);
DISPLAY 0.680851 (-1760 4985);
PAINT MONO (-1760 4985);
FORCEPROP 0 LASTPIN (-1750 5025) $PN 284
J 2
(-1760 5035);
DISPLAY 0.680851 (-1760 5035);
PAINT MONO (-1760 5035);
FORCEPROP 0 LASTPIN (-1750 5075) $PN 286
J 2
(-1760 5085);
DISPLAY 0.680851 (-1760 5085);
PAINT MONO (-1760 5085);
FORCEPROP 0 LASTPIN (-1750 5125) $PN 288
J 2
(-1760 5135);
DISPLAY 0.680851 (-1760 5135);
PAINT MONO (-1760 5135);
FORCEPROP 2 LAST PART_TYPE SMLF
J 0
(-1600 5700);
DISPLAY 1.021277 (-1600 5700);
FORCEPROP 1 LAST MATERIAL IO
J 0
(-1600 5450);
DISPLAY 0.468085 (-1600 5450);
PAINT SKYBLUE (-1600 5450);
FORCEPROP 2 LAST VALUE SCONN288_DDR506112002KQ
J 0
(-1600 5650);
DISPLAY 0.489362 (-1600 5650);
PAINT SKYBLUE (-1600 5650);
FORCEPROP 1 LAST PART_NUMBER DFHST8FS479
J 0
(-1600 5525);
DISPLAY 0.468085 (-1600 5525);
PAINT SKYBLUE (-1600 5525);
FORCEPROP 1 LAST CDS_LMAN_SYM_OUTLINE -450,1800,450,-1750
J 0
(-1150 3625);
DISPLAY 0.468085 (-1150 3625);
PAINT GREEN (-1150 3625);
DISPLAY INVISIBLE (-1150 3625);
FORCEPROP 1 LAST PATH I177
J 0
(-1150 3625);
DISPLAY 0.723404 (-1150 3625);
PAINT GREEN (-1150 3625);
DISPLAY INVISIBLE (-1150 3625);
FORCEPROP 1 LAST NEEDS_NO_SIZE TRUE
J 0
(-1150 3625);
DISPLAY 0.723404 (-1150 3625);
PAINT GREEN (-1150 3625);
DISPLAY INVISIBLE (-1150 3625);
FORCEPROP 2 LAST CDS_LIB pure_quanta
J 0
(-1150 3625);
DISPLAY INVISIBLE (-1150 3625);
FORCEADD OFFPAGE..6
(-8250 2775);
FORCEPROP 2 LAST $XR5 136 
J 0
(-9009 2775);
DISPLAY 0.638298 (-9009 2775);
PAINT MONO (-9009 2775);
FORCEPROP 2 LAST $XR4 96 
J 0
(-8889 2775);
DISPLAY 0.638298 (-8889 2775);
PAINT MONO (-8889 2775);
FORCEPROP 2 LAST $XR3 95 
J 0
(-8799 2775);
DISPLAY 0.638298 (-8799 2775);
PAINT MONO (-8799 2775);
FORCEPROP 2 LAST $XR2 93 
J 0
(-8709 2775);
DISPLAY 0.638298 (-8709 2775);
PAINT MONO (-8709 2775);
FORCEPROP 2 LAST $XR1 92 
J 0
(-8619 2775);
DISPLAY 0.638298 (-8619 2775);
PAINT MONO (-8619 2775);
FORCEPROP 2 LAST $XR0 91 
J 0
(-8529 2775);
DISPLAY 0.638298 (-8529 2775);
PAINT MONO (-8529 2775);
FORCEPROP 2 LAST PATH I179
J 0
(-8550 2825);
DISPLAY 1.021277 (-8550 2825);
DISPLAY INVISIBLE (-8550 2825);
FORCEPROP 1 LAST COMMENT_BODY TRUE
J 0
(-8150 2700);
DISPLAY 0.872340 (-8150 2700);
PAINT GREEN (-8150 2700);
DISPLAY INVISIBLE (-8150 2700);
FORCEPROP 1 LAST OFFPAGE TRUE
J 0
(-7925 2650);
DISPLAY 0.872340 (-7925 2650);
PAINT GREEN (-7925 2650);
DISPLAY INVISIBLE (-7925 2650);
FORCEPROP 2 LAST CDS_LIB mstr_standard
J 0
(-8250 2775);
DISPLAY 0.808511 (-8250 2775);
DISPLAY INVISIBLE (-8250 2775);
FORCEADD OFFPAGE..1
(-8250 4475);
FORCEPROP 2 LAST $XR0 19 
J 0
(-8501 4475);
DISPLAY 0.638298 (-8501 4475);
PAINT MONO (-8501 4475);
FORCEPROP 2 LAST PATH I18
J 0
(-8200 4550);
DISPLAY 1.021277 (-8200 4550);
DISPLAY INVISIBLE (-8200 4550);
FORCEPROP 1 LAST COMMENT_BODY TRUE
J 0
(-8125 4375);
DISPLAY 0.872340 (-8125 4375);
PAINT GREEN (-8125 4375);
DISPLAY INVISIBLE (-8125 4375);
FORCEPROP 1 LAST OFFPAGE TRUE
J 0
(-7925 4350);
DISPLAY 0.872340 (-7925 4350);
PAINT GREEN (-7925 4350);
DISPLAY INVISIBLE (-7925 4350);
FORCEPROP 2 LAST CDS_LIB mstr_standard
J 0
(-8250 4475);
DISPLAY 0.808511 (-8250 4475);
DISPLAY INVISIBLE (-8250 4475);
FORCEADD Q_CAP..1
R 2
(-8550 3175);
FORCEPROP 1 LAST LOCATION C124
J 2
(-8600 3275);
DISPLAY 0.489362 (-8600 3275);
PAINT SKYBLUE (-8600 3275);
FORCEPROP 0 LAST $SEC 1
J 0
(-8600 3325);
DISPLAY 0.680851 (-8600 3325);
PAINT MONO (-8600 3325);
DISPLAY INVISIBLE (-8600 3325);
FORCEPROP 0 LAST CDS_SEC 1
J 0
(-8600 3325);
DISPLAY 1.021277 (-8600 3325);
DISPLAY INVISIBLE (-8600 3325);
FORCEPROP 1 LASTPIN (-8550 3275) $PN 1
J 2
(-8560 3255);
DISPLAY 0.489362 (-8560 3255);
PAINT MONO (-8560 3255);
FORCEPROP 1 LASTPIN (-8550 3075) $PN 2
J 2
(-8560 3055);
DISPLAY 0.489362 (-8560 3055);
PAINT MONO (-8560 3055);
FORCEPROP 1 LAST MATERIAL X7R
J 2
(-8600 3075);
DISPLAY 0.489362 (-8600 3075);
PAINT SKYBLUE (-8600 3075);
FORCEPROP 1 LAST TOLERANCE 10%
J 2
(-8600 3125);
DISPLAY 0.489362 (-8600 3125);
PAINT SKYBLUE (-8600 3125);
FORCEPROP 1 LAST VALUE 0.1UF
J 2
(-8600 3225);
DISPLAY 0.489362 (-8600 3225);
PAINT SKYBLUE (-8600 3225);
FORCEPROP 1 LAST VOLTAGE 25V
J 2
(-8600 3175);
DISPLAY 0.489362 (-8600 3175);
PAINT SKYBLUE (-8600 3175);
FORCEPROP 1 LAST PART_NUMBER CH4104K1B00
J 2
(-8600 3025);
DISPLAY 0.489362 (-8600 3025);
PAINT SKYBLUE (-8600 3025);
FORCEPROP 1 LAST PACK_TYPE 0402
J 2
(-8600 2975);
DISPLAY 0.489362 (-8600 2975);
PAINT SKYBLUE (-8600 2975);
FORCEPROP 0 LAST BOM_COST MEM
J 2
(-8605 3320);
DISPLAY 0.595745 (-8605 3320);
PAINT MONO (-8605 3320);
DISPLAY INVISIBLE (-8605 3320);
FORCEPROP 2 LAST CDS_LIB pure_quanta
J 0
(-8550 3175);
DISPLAY INVISIBLE (-8550 3175);
FORCEPROP 1 LAST PATH I185
J 2
(-8600 3325);
DISPLAY 0.978723 (-8600 3325);
PAINT WHITE (-8600 3325);
DISPLAY INVISIBLE (-8600 3325);
FORCEPROP 0 LAST ROOM MEM_CH_A_CPU0_DIMM1
J 2
(-8605 3320);
DISPLAY 0.595745 (-8605 3320);
PAINT RED (-8605 3320);
DISPLAY INVISIBLE (-8605 3320);
FORCEADD GND..1
(-8550 2950);
FORCEPROP 3 LASTPIN (-8550 3000) SIG_NAME GND\g
J 0
(-8540 3010);
DISPLAY 0.659574 (-8540 3010);
PAINT MONO (-8540 3010);
DISPLAY INVISIBLE (-8540 3010);
FORCEPROP 2 LAST BOM_COST MEM
J 0
(-8525 3075);
DISPLAY 0.659574 (-8525 3075);
DISPLAY INVISIBLE (-8525 3075);
FORCEPROP 1 LAST SIZE 1B
J 0
(-8475 2900);
DISPLAY 0.723404 (-8475 2900);
PAINT GREEN (-8475 2900);
DISPLAY INVISIBLE (-8475 2900);
FORCEPROP 2 LAST CDS_LIB mstr_symbols
J 0
(-8550 2950);
DISPLAY 0.808511 (-8550 2950);
DISPLAY INVISIBLE (-8550 2950);
FORCEPROP 1 LAST BODY_TYPE PLUMBING
J 0
(-8595 2907);
DISPLAY 0.276596 (-8595 2907);
PAINT GREEN (-8595 2907);
DISPLAY INVISIBLE (-8595 2907);
FORCEPROP 1 LAST PATH I186
J 0
(-8475 2950);
DISPLAY 0.872340 (-8475 2950);
PAINT AQUA (-8475 2950);
DISPLAY INVISIBLE (-8475 2950);
FORCEPROP 1 LAST VOLTAGE 0
J 0
(-8570 3045);
DISPLAY 0.829787 (-8570 3045);
PAINT SKYBLUE (-8570 3045);
DISPLAY INVISIBLE (-8570 3045);
FORCEPROP 2 LAST ROOM MEM_EFGH_DECOUPLING_CAPS
J 0
(-8525 3025);
DISPLAY 0.659574 (-8525 3025);
PAINT RED (-8525 3025);
DISPLAY INVISIBLE (-8525 3025);
FORCEPROP 1 LAST HDL_POWER GND
J 0
(-8550 3100);
DISPLAY 0.723404 (-8550 3100);
PAINT GREEN (-8550 3100);
DISPLAY INVISIBLE (-8550 3100);
FORCEADD OFFPAGE..6
(-9000 2075);
FORCEPROP 2 LAST $XR5 81 
J 0
(-9429 2039);
DISPLAY 0.638298 (-9429 2039);
PAINT MONO (-9429 2039);
FORCEPROP 2 LAST $XR4 96 
J 0
(-9339 2039);
DISPLAY 0.638298 (-9339 2039);
PAINT MONO (-9339 2039);
FORCEPROP 2 LAST $XR3 95 
J 0
(-9249 2039);
DISPLAY 0.638298 (-9249 2039);
PAINT MONO (-9249 2039);
FORCEPROP 2 LAST $XR2 93 
J 0
(-9429 2075);
DISPLAY 0.638298 (-9429 2075);
PAINT MONO (-9429 2075);
FORCEPROP 2 LAST $XR1 92 
J 0
(-9339 2075);
DISPLAY 0.638298 (-9339 2075);
PAINT MONO (-9339 2075);
FORCEPROP 2 LAST $XR0 91 
J 0
(-9249 2075);
DISPLAY 0.638298 (-9249 2075);
PAINT MONO (-9249 2075);
FORCEPROP 2 LAST PATH I187
J 0
(-8950 2150);
DISPLAY 1.021277 (-8950 2150);
DISPLAY INVISIBLE (-8950 2150);
FORCEPROP 1 LAST COMMENT_BODY TRUE
J 0
(-8900 2000);
DISPLAY 0.872340 (-8900 2000);
PAINT GREEN (-8900 2000);
DISPLAY INVISIBLE (-8900 2000);
FORCEPROP 1 LAST OFFPAGE TRUE
J 0
(-8675 1950);
DISPLAY 0.872340 (-8675 1950);
PAINT GREEN (-8675 1950);
DISPLAY INVISIBLE (-8675 1950);
FORCEPROP 2 LAST CDS_LIB mstr_standard
J 0
(-9000 2075);
DISPLAY INVISIBLE (-9000 2075);
FORCEADD Q_RES..1
R 2
(-8450 2075);
FORCEPROP 1 LAST LOCATION R300
J 2
(-8400 2125);
DISPLAY 0.489362 (-8400 2125);
PAINT SKYBLUE (-8400 2125);
FORCEPROP 0 LAST $SEC 1
J 0
(-8400 2175);
DISPLAY 0.680851 (-8400 2175);
PAINT MONO (-8400 2175);
DISPLAY INVISIBLE (-8400 2175);
FORCEPROP 0 LAST CDS_SEC 1
J 0
(-8400 2175);
DISPLAY 1.021277 (-8400 2175);
DISPLAY INVISIBLE (-8400 2175);
FORCEPROP 1 LASTPIN (-8350 2075) $PN 1
J 2
(-8362 2087);
DISPLAY 0.489362 (-8362 2087);
PAINT MONO (-8362 2087);
FORCEPROP 1 LASTPIN (-8550 2075) $PN 2
J 2
(-8512 2087);
DISPLAY 0.489362 (-8512 2087);
PAINT MONO (-8512 2087);
FORCEPROP 1 LAST VALUE 0
J 0
(-8450 2025);
DISPLAY 0.489362 (-8450 2025);
PAINT SKYBLUE (-8450 2025);
FORCEPROP 2 LAST CDS_LIB pure_quanta
J 0
(-8450 2075);
DISPLAY INVISIBLE (-8450 2075);
FORCEPROP 2 LAST BOM_COST MEM
J 0
(-8475 2225);
DISPLAY 0.744681 (-8475 2225);
PAINT WHITE (-8475 2225);
DISPLAY INVISIBLE (-8475 2225);
FORCEPROP 1 LAST PATH I188
J 2
(-8400 2225);
DISPLAY 0.978723 (-8400 2225);
PAINT WHITE (-8400 2225);
DISPLAY INVISIBLE (-8400 2225);
FORCEPROP 1 LAST WATTAGE 1/16W
J 0
(-8375 2000);
DISPLAY 0.489362 (-8375 2000);
PAINT SKYBLUE (-8375 2000);
DISPLAY INVISIBLE (-8375 2000);
FORCEPROP 1 LAST MATERIAL CHIP
J 0
(-8625 2050);
DISPLAY 0.489362 (-8625 2050);
PAINT SKYBLUE (-8625 2050);
DISPLAY INVISIBLE (-8625 2050);
FORCEPROP 1 LAST TOLERANCE 5%
J 2
(-8325 2050);
DISPLAY 0.489362 (-8325 2050);
PAINT SKYBLUE (-8325 2050);
DISPLAY INVISIBLE (-8325 2050);
FORCEPROP 1 LAST PART_NUMBER CS00002JB38
J 0
(-8550 2125);
DISPLAY 0.489362 (-8550 2125);
PAINT SKYBLUE (-8550 2125);
DISPLAY INVISIBLE (-8550 2125);
FORCEPROP 1 LAST PACK_TYPE 0402LF
J 0
(-8625 2000);
DISPLAY 0.489362 (-8625 2000);
PAINT SKYBLUE (-8625 2000);
DISPLAY INVISIBLE (-8625 2000);
FORCEPROP 2 LAST ROOM RST_CPU0_PLD_TO_DIMM
J 0
(-8475 2175);
DISPLAY 0.744681 (-8475 2175);
PAINT RED (-8475 2175);
DISPLAY INVISIBLE (-8475 2175);
FORCEADD Q_RES..2
(-8325 2225);
FORCEPROP 1 LAST LOCATION R99
J 0
(-8280 2350);
DISPLAY 0.489362 (-8280 2350);
PAINT SKYBLUE (-8280 2350);
FORCEPROP 0 LAST $SEC 1
J 0
(-8275 2400);
DISPLAY 0.680851 (-8275 2400);
PAINT MONO (-8275 2400);
DISPLAY INVISIBLE (-8275 2400);
FORCEPROP 0 LAST CDS_SEC 1
J 0
(-8275 2400);
DISPLAY 1.021277 (-8275 2400);
DISPLAY INVISIBLE (-8275 2400);
FORCEPROP 1 LASTPIN (-8325 2325) $PN 1
J 0
(-8320 2287);
DISPLAY 0.489362 (-8320 2287);
PAINT MONO (-8320 2287);
FORCEPROP 1 LASTPIN (-8325 2125) $PN 2
J 0
(-8320 2135);
DISPLAY 0.489362 (-8320 2135);
PAINT MONO (-8320 2135);
FORCEPROP 1 LAST WATTAGE 1/16W
J 0
(-8275 2250);
DISPLAY 0.489362 (-8275 2250);
PAINT SKYBLUE (-8275 2250);
FORCEPROP 1 LAST MATERIAL EMPTY
J 0
(-8275 2225);
DISPLAY 0.489362 (-8275 2225);
PAINT RED (-8275 2225);
FORCEPROP 1 LAST TOLERANCE 5%
J 0
(-8275 2275);
DISPLAY 0.489362 (-8275 2275);
PAINT SKYBLUE (-8275 2275);
FORCEPROP 1 LAST VALUE 1K
J 0
(-8280 2300);
DISPLAY 0.489362 (-8280 2300);
PAINT SKYBLUE (-8280 2300);
FORCEPROP 1 LAST PACK_TYPE 0402LF
J 0
(-8275 2175);
DISPLAY 0.489362 (-8275 2175);
PAINT SKYBLUE (-8275 2175);
FORCEPROP 2 LAST CDS_LIB pure_quanta
J 0
(-8325 2225);
DISPLAY INVISIBLE (-8325 2225);
FORCEPROP 2 LAST BOM_COST MEM
J 0
(-8275 2400);
DISPLAY 0.808511 (-8275 2400);
DISPLAY INVISIBLE (-8275 2400);
FORCEPROP 1 LAST PATH I189
J 0
(-8275 2400);
DISPLAY 0.978723 (-8275 2400);
PAINT WHITE (-8275 2400);
DISPLAY INVISIBLE (-8275 2400);
FORCEPROP 1 LAST PART_NUMBER TMP_QCS21002JB34
J 0
(-8275 2200);
DISPLAY 0.489362 (-8275 2200);
PAINT SKYBLUE (-8275 2200);
DISPLAY INVISIBLE (-8275 2200);
FORCEPROP 2 LAST ROOM MEM_CH_A_CPU0_DIMM1
J 0
(-8275 2450);
DISPLAY 0.808511 (-8275 2450);
PAINT RED (-8275 2450);
DISPLAY INVISIBLE (-8275 2450);
FORCEADD OFFPAGE..1
(-8250 4325);
FORCEPROP 2 LAST $XR0 19 
J 0
(-8501 4325);
DISPLAY 0.638298 (-8501 4325);
PAINT MONO (-8501 4325);
FORCEPROP 2 LAST PATH I19
J 0
(-8200 4400);
DISPLAY 1.021277 (-8200 4400);
DISPLAY INVISIBLE (-8200 4400);
FORCEPROP 1 LAST COMMENT_BODY TRUE
J 0
(-8125 4225);
DISPLAY 0.872340 (-8125 4225);
PAINT GREEN (-8125 4225);
DISPLAY INVISIBLE (-8125 4225);
FORCEPROP 1 LAST OFFPAGE TRUE
J 0
(-7925 4200);
DISPLAY 0.872340 (-7925 4200);
PAINT GREEN (-7925 4200);
DISPLAY INVISIBLE (-7925 4200);
FORCEPROP 2 LAST CDS_LIB mstr_standard
J 0
(-8250 4325);
DISPLAY 0.808511 (-8250 4325);
DISPLAY INVISIBLE (-8250 4325);
FORCEADD VCC_CORE..1
(-8325 2400);
FORCEPROP 3 LASTPIN (-8325 2350) SIG_NAME P3V3_STBY\g
J 0
(-8315 2360);
DISPLAY 0.659574 (-8315 2360);
PAINT MONO (-8315 2360);
DISPLAY INVISIBLE (-8315 2360);
FORCEPROP 1 LAST HDL_POWER P3V3_STBY
J 1
(-8325 2450);
DISPLAY 0.489362 (-8325 2450);
PAINT GREEN (-8325 2450);
FORCEPROP 2 LAST CDS_LIB mstr_symbols
J 0
(-8325 2400);
DISPLAY INVISIBLE (-8325 2400);
FORCEPROP 1 LAST PATH I190
J 0
(-8275 2425);
DISPLAY 0.872340 (-8275 2425);
PAINT AQUA (-8275 2425);
DISPLAY INVISIBLE (-8275 2425);
FORCEPROP 0 LAST VOLTAGE 3.3
J 0
(-8600 2550);
DISPLAY 1.021277 (-8600 2550);
PAINT SKYBLUE (-8600 2550);
DISPLAY INVISIBLE (-8600 2550);
FORCEPROP 2 LAST ROOM PVCCINFAON_CPU0_CTRL
J 0
(-8325 2500);
DISPLAY 0.808511 (-8325 2500);
PAINT RED (-8325 2500);
DISPLAY INVISIBLE (-8325 2500);
FORCEADD OFFPAGE..2
(-2375 4275);
FORCEPROP 2 LAST $XR0 19 
J 0
(-2186 4275);
DISPLAY 0.638298 (-2186 4275);
PAINT MONO (-2186 4275);
FORCEPROP 1 LAST COMMENT_BODY TRUE
J 0
(-2420 4180);
DISPLAY 0.872340 (-2420 4180);
PAINT GREEN (-2420 4180);
DISPLAY INVISIBLE (-2420 4180);
FORCEPROP 1 LAST OFFPAGE TRUE
J 0
(-2050 4150);
DISPLAY 0.723404 (-2050 4150);
PAINT GREEN (-2050 4150);
DISPLAY INVISIBLE (-2050 4150);
FORCEPROP 2 LAST CDS_LIB mstr_standard
J 0
(-2375 4275);
DISPLAY 0.723404 (-2375 4275);
PAINT MONO (-2375 4275);
DISPLAY INVISIBLE (-2375 4275);
FORCEPROP 2 LAST PATH I192
J 0
(-2175 4325);
DISPLAY 0.680851 (-2175 4325);
DISPLAY INVISIBLE (-2175 4325);
FORCEADD OFFPAGE..2
(-2375 4225);
FORCEPROP 2 LAST $XR0 19 
J 0
(-2186 4225);
DISPLAY 0.638298 (-2186 4225);
PAINT MONO (-2186 4225);
FORCEPROP 1 LAST COMMENT_BODY TRUE
J 0
(-2420 4130);
DISPLAY 0.872340 (-2420 4130);
PAINT GREEN (-2420 4130);
DISPLAY INVISIBLE (-2420 4130);
FORCEPROP 1 LAST OFFPAGE TRUE
J 0
(-2050 4100);
DISPLAY 0.723404 (-2050 4100);
PAINT GREEN (-2050 4100);
DISPLAY INVISIBLE (-2050 4100);
FORCEPROP 2 LAST CDS_LIB mstr_standard
J 0
(-2375 4225);
DISPLAY 0.723404 (-2375 4225);
PAINT MONO (-2375 4225);
DISPLAY INVISIBLE (-2375 4225);
FORCEPROP 2 LAST PATH I193
J 0
(-2175 4275);
DISPLAY 0.680851 (-2175 4275);
DISPLAY INVISIBLE (-2175 4275);
FORCEADD OFFPAGE..2
(-2375 3175);
FORCEPROP 2 LAST $XR0 19 
J 0
(-2186 3175);
DISPLAY 0.638298 (-2186 3175);
PAINT MONO (-2186 3175);
FORCEPROP 1 LAST COMMENT_BODY TRUE
J 0
(-2420 3080);
DISPLAY 0.872340 (-2420 3080);
PAINT GREEN (-2420 3080);
DISPLAY INVISIBLE (-2420 3080);
FORCEPROP 1 LAST OFFPAGE TRUE
J 0
(-2050 3050);
DISPLAY 0.723404 (-2050 3050);
PAINT GREEN (-2050 3050);
DISPLAY INVISIBLE (-2050 3050);
FORCEPROP 2 LAST CDS_LIB mstr_standard
J 0
(-2375 3175);
DISPLAY 0.723404 (-2375 3175);
PAINT MONO (-2375 3175);
DISPLAY INVISIBLE (-2375 3175);
FORCEPROP 2 LAST PATH I194
J 0
(-2175 3225);
DISPLAY 0.680851 (-2175 3225);
DISPLAY INVISIBLE (-2175 3225);
FORCEADD OFFPAGE..2
(-2375 3225);
FORCEPROP 2 LAST $XR0 19 
J 0
(-2186 3225);
DISPLAY 0.638298 (-2186 3225);
PAINT MONO (-2186 3225);
FORCEPROP 1 LAST COMMENT_BODY TRUE
J 0
(-2420 3130);
DISPLAY 0.872340 (-2420 3130);
PAINT GREEN (-2420 3130);
DISPLAY INVISIBLE (-2420 3130);
FORCEPROP 1 LAST OFFPAGE TRUE
J 0
(-2050 3100);
DISPLAY 0.723404 (-2050 3100);
PAINT GREEN (-2050 3100);
DISPLAY INVISIBLE (-2050 3100);
FORCEPROP 2 LAST CDS_LIB mstr_standard
J 0
(-2375 3225);
DISPLAY 0.723404 (-2375 3225);
PAINT MONO (-2375 3225);
DISPLAY INVISIBLE (-2375 3225);
FORCEPROP 2 LAST PATH I195
J 0
(-2175 3275);
DISPLAY 0.680851 (-2175 3275);
DISPLAY INVISIBLE (-2175 3275);
FORCEADD TAP..1
(-3175 4075);
FORCEPROP 3 LASTPIN (-3225 4075) SIG_NAME M_J_CPU0_SA_DQS_DN<8>
J 0
(-3215 4085);
DISPLAY 0.659574 (-3215 4085);
PAINT MONO (-3215 4085);
DISPLAY INVISIBLE (-3215 4085);
FORCEPROP 1 LASTPIN (-3225 4075) BN 8
J 0
(-3237 4083);
DISPLAY 0.489362 (-3237 4083);
PAINT GREEN (-3237 4083);
FORCEPROP 2 LAST CDS_LIB mstr_standard
J 0
(-3175 4075);
DISPLAY 0.723404 (-3175 4075);
PAINT MONO (-3175 4075);
DISPLAY INVISIBLE (-3175 4075);
FORCEPROP 1 LAST BODY_TYPE PLUMBING
J 0
(-3175 4125);
DISPLAY 0.872340 (-3175 4125);
PAINT GREEN (-3175 4125);
DISPLAY INVISIBLE (-3175 4125);
FORCEPROP 1 LAST HDL_TAP TRUE
J 0
(-2850 3950);
DISPLAY 0.872340 (-2850 3950);
DISPLAY INVISIBLE (-2850 3950);
FORCEPROP 1 LAST PATH I196
J 0
(-3177 4075);
DISPLAY 0.872340 (-3177 4075);
PAINT GREEN (-3177 4075);
DISPLAY INVISIBLE (-3177 4075);
FORCEADD TAP..1
(-3175 4175);
FORCEPROP 3 LASTPIN (-3225 4175) SIG_NAME M_J_CPU0_SA_DQS_DN<9>
J 0
(-3215 4185);
DISPLAY 0.659574 (-3215 4185);
PAINT MONO (-3215 4185);
DISPLAY INVISIBLE (-3215 4185);
FORCEPROP 1 LASTPIN (-3225 4175) BN 9
J 0
(-3237 4183);
DISPLAY 0.489362 (-3237 4183);
PAINT GREEN (-3237 4183);
FORCEPROP 2 LAST CDS_LIB mstr_standard
J 0
(-3175 4175);
DISPLAY 0.723404 (-3175 4175);
PAINT MONO (-3175 4175);
DISPLAY INVISIBLE (-3175 4175);
FORCEPROP 1 LAST BODY_TYPE PLUMBING
J 0
(-3175 4225);
DISPLAY 0.872340 (-3175 4225);
PAINT GREEN (-3175 4225);
DISPLAY INVISIBLE (-3175 4225);
FORCEPROP 1 LAST HDL_TAP TRUE
J 0
(-2850 4050);
DISPLAY 0.872340 (-2850 4050);
DISPLAY INVISIBLE (-2850 4050);
FORCEPROP 1 LAST PATH I197
J 0
(-3177 4175);
DISPLAY 0.872340 (-3177 4175);
PAINT GREEN (-3177 4175);
DISPLAY INVISIBLE (-3177 4175);
FORCEADD TAP..1
(-3375 4225);
FORCEPROP 3 LASTPIN (-3425 4225) SIG_NAME M_J_CPU0_SA_DQS_DP<9>
J 0
(-3415 4235);
DISPLAY 0.659574 (-3415 4235);
PAINT MONO (-3415 4235);
DISPLAY INVISIBLE (-3415 4235);
FORCEPROP 1 LASTPIN (-3425 4225) BN 9
J 0
(-3437 4233);
DISPLAY 0.489362 (-3437 4233);
PAINT GREEN (-3437 4233);
FORCEPROP 2 LAST CDS_LIB mstr_standard
J 0
(-3375 4225);
DISPLAY 0.723404 (-3375 4225);
PAINT MONO (-3375 4225);
DISPLAY INVISIBLE (-3375 4225);
FORCEPROP 1 LAST BODY_TYPE PLUMBING
J 0
(-3375 4275);
DISPLAY 0.872340 (-3375 4275);
PAINT GREEN (-3375 4275);
DISPLAY INVISIBLE (-3375 4275);
FORCEPROP 1 LAST HDL_TAP TRUE
J 0
(-3050 4100);
DISPLAY 0.872340 (-3050 4100);
DISPLAY INVISIBLE (-3050 4100);
FORCEPROP 1 LAST PATH I198
J 0
(-3377 4225);
DISPLAY 0.872340 (-3377 4225);
PAINT GREEN (-3377 4225);
DISPLAY INVISIBLE (-3377 4225);
FORCEADD TAP..1
(-3375 4125);
FORCEPROP 3 LASTPIN (-3425 4125) SIG_NAME M_J_CPU0_SA_DQS_DP<8>
J 0
(-3415 4135);
DISPLAY 0.659574 (-3415 4135);
PAINT MONO (-3415 4135);
DISPLAY INVISIBLE (-3415 4135);
FORCEPROP 1 LASTPIN (-3425 4125) BN 8
J 0
(-3437 4133);
DISPLAY 0.489362 (-3437 4133);
PAINT GREEN (-3437 4133);
FORCEPROP 2 LAST CDS_LIB mstr_standard
J 0
(-3375 4125);
DISPLAY 0.723404 (-3375 4125);
PAINT MONO (-3375 4125);
DISPLAY INVISIBLE (-3375 4125);
FORCEPROP 1 LAST BODY_TYPE PLUMBING
J 0
(-3375 4175);
DISPLAY 0.872340 (-3375 4175);
PAINT GREEN (-3375 4175);
DISPLAY INVISIBLE (-3375 4175);
FORCEPROP 1 LAST HDL_TAP TRUE
J 0
(-3050 4000);
DISPLAY 0.872340 (-3050 4000);
DISPLAY INVISIBLE (-3050 4000);
FORCEPROP 1 LAST PATH I199
J 0
(-3377 4125);
DISPLAY 0.872340 (-3377 4125);
PAINT GREEN (-3377 4125);
DISPLAY INVISIBLE (-3377 4125);
FORCEADD OFFPAGE..5
(-8250 1925);
FORCEPROP 2 LAST $XR0 19 
J 0
(-8474 1925);
DISPLAY 0.638298 (-8474 1925);
PAINT MONO (-8474 1925);
FORCEPROP 2 LAST PATH I2
J 0
(-8200 2000);
DISPLAY 1.021277 (-8200 2000);
DISPLAY INVISIBLE (-8200 2000);
FORCEPROP 1 LAST COMMENT_BODY TRUE
J 0
(-8150 1850);
DISPLAY 0.872340 (-8150 1850);
PAINT GREEN (-8150 1850);
DISPLAY INVISIBLE (-8150 1850);
FORCEPROP 1 LAST OFFPAGE TRUE
J 0
(-7925 1800);
DISPLAY 0.872340 (-7925 1800);
PAINT GREEN (-7925 1800);
DISPLAY INVISIBLE (-7925 1800);
FORCEPROP 2 LAST CDS_LIB mstr_standard
J 0
(-8250 1925);
DISPLAY 0.808511 (-8250 1925);
DISPLAY INVISIBLE (-8250 1925);
FORCEADD OFFPAGE..1
(-8250 5375);
FORCEPROP 2 LAST $XR0 19 
J 0
(-8501 5375);
DISPLAY 0.638298 (-8501 5375);
PAINT MONO (-8501 5375);
FORCEPROP 2 LAST PATH I20
J 0
(-8200 5450);
DISPLAY 1.021277 (-8200 5450);
DISPLAY INVISIBLE (-8200 5450);
FORCEPROP 1 LAST COMMENT_BODY TRUE
J 0
(-8125 5275);
DISPLAY 0.872340 (-8125 5275);
PAINT GREEN (-8125 5275);
DISPLAY INVISIBLE (-8125 5275);
FORCEPROP 1 LAST OFFPAGE TRUE
J 0
(-7925 5250);
DISPLAY 0.872340 (-7925 5250);
PAINT GREEN (-7925 5250);
DISPLAY INVISIBLE (-7925 5250);
FORCEPROP 2 LAST CDS_LIB mstr_standard
J 0
(-8250 5375);
DISPLAY 0.723404 (-8250 5375);
PAINT MONO (-8250 5375);
DISPLAY INVISIBLE (-8250 5375);
FORCEADD TAP..1
(-3175 3975);
FORCEPROP 3 LASTPIN (-3225 3975) SIG_NAME M_J_CPU0_SA_DQS_DN<7>
J 0
(-3215 3985);
DISPLAY 0.659574 (-3215 3985);
PAINT MONO (-3215 3985);
DISPLAY INVISIBLE (-3215 3985);
FORCEPROP 1 LASTPIN (-3225 3975) BN 7
J 0
(-3237 3983);
DISPLAY 0.489362 (-3237 3983);
PAINT GREEN (-3237 3983);
FORCEPROP 2 LAST CDS_LIB mstr_standard
J 0
(-3175 3975);
DISPLAY 0.723404 (-3175 3975);
PAINT MONO (-3175 3975);
DISPLAY INVISIBLE (-3175 3975);
FORCEPROP 1 LAST BODY_TYPE PLUMBING
J 0
(-3175 4025);
DISPLAY 0.872340 (-3175 4025);
PAINT GREEN (-3175 4025);
DISPLAY INVISIBLE (-3175 4025);
FORCEPROP 1 LAST HDL_TAP TRUE
J 0
(-2850 3850);
DISPLAY 0.872340 (-2850 3850);
DISPLAY INVISIBLE (-2850 3850);
FORCEPROP 1 LAST PATH I200
J 0
(-3177 3975);
DISPLAY 0.872340 (-3177 3975);
PAINT GREEN (-3177 3975);
DISPLAY INVISIBLE (-3177 3975);
FORCEADD TAP..1
(-3175 3875);
FORCEPROP 3 LASTPIN (-3225 3875) SIG_NAME M_J_CPU0_SA_DQS_DN<6>
J 0
(-3215 3885);
DISPLAY 0.659574 (-3215 3885);
PAINT MONO (-3215 3885);
DISPLAY INVISIBLE (-3215 3885);
FORCEPROP 1 LASTPIN (-3225 3875) BN 6
J 0
(-3237 3883);
DISPLAY 0.489362 (-3237 3883);
PAINT GREEN (-3237 3883);
FORCEPROP 2 LAST CDS_LIB mstr_standard
J 0
(-3175 3875);
DISPLAY 0.723404 (-3175 3875);
PAINT MONO (-3175 3875);
DISPLAY INVISIBLE (-3175 3875);
FORCEPROP 1 LAST BODY_TYPE PLUMBING
J 0
(-3175 3925);
DISPLAY 0.872340 (-3175 3925);
PAINT GREEN (-3175 3925);
DISPLAY INVISIBLE (-3175 3925);
FORCEPROP 1 LAST HDL_TAP TRUE
J 0
(-2850 3750);
DISPLAY 0.872340 (-2850 3750);
DISPLAY INVISIBLE (-2850 3750);
FORCEPROP 1 LAST PATH I201
J 0
(-3177 3875);
DISPLAY 0.872340 (-3177 3875);
PAINT GREEN (-3177 3875);
DISPLAY INVISIBLE (-3177 3875);
FORCEADD TAP..1
(-3175 3775);
FORCEPROP 3 LASTPIN (-3225 3775) SIG_NAME M_J_CPU0_SA_DQS_DN<5>
J 0
(-3215 3785);
DISPLAY 0.659574 (-3215 3785);
PAINT MONO (-3215 3785);
DISPLAY INVISIBLE (-3215 3785);
FORCEPROP 1 LASTPIN (-3225 3775) BN 5
J 0
(-3237 3783);
DISPLAY 0.489362 (-3237 3783);
PAINT GREEN (-3237 3783);
FORCEPROP 2 LAST CDS_LIB mstr_standard
J 0
(-3175 3775);
DISPLAY 0.723404 (-3175 3775);
PAINT MONO (-3175 3775);
DISPLAY INVISIBLE (-3175 3775);
FORCEPROP 1 LAST BODY_TYPE PLUMBING
J 0
(-3175 3825);
DISPLAY 0.872340 (-3175 3825);
PAINT GREEN (-3175 3825);
DISPLAY INVISIBLE (-3175 3825);
FORCEPROP 1 LAST HDL_TAP TRUE
J 0
(-2850 3650);
DISPLAY 0.872340 (-2850 3650);
DISPLAY INVISIBLE (-2850 3650);
FORCEPROP 1 LAST PATH I202
J 0
(-3177 3775);
DISPLAY 0.872340 (-3177 3775);
PAINT GREEN (-3177 3775);
DISPLAY INVISIBLE (-3177 3775);
FORCEADD TAP..1
(-3175 3675);
FORCEPROP 3 LASTPIN (-3225 3675) SIG_NAME M_J_CPU0_SA_DQS_DN<4>
J 0
(-3215 3685);
DISPLAY 0.659574 (-3215 3685);
PAINT MONO (-3215 3685);
DISPLAY INVISIBLE (-3215 3685);
FORCEPROP 1 LASTPIN (-3225 3675) BN 4
J 0
(-3237 3683);
DISPLAY 0.489362 (-3237 3683);
PAINT GREEN (-3237 3683);
FORCEPROP 2 LAST CDS_LIB mstr_standard
J 0
(-3175 3675);
DISPLAY 0.723404 (-3175 3675);
PAINT MONO (-3175 3675);
DISPLAY INVISIBLE (-3175 3675);
FORCEPROP 1 LAST BODY_TYPE PLUMBING
J 0
(-3175 3725);
DISPLAY 0.872340 (-3175 3725);
PAINT GREEN (-3175 3725);
DISPLAY INVISIBLE (-3175 3725);
FORCEPROP 1 LAST HDL_TAP TRUE
J 0
(-2850 3550);
DISPLAY 0.872340 (-2850 3550);
DISPLAY INVISIBLE (-2850 3550);
FORCEPROP 1 LAST PATH I203
J 0
(-3177 3675);
DISPLAY 0.872340 (-3177 3675);
PAINT GREEN (-3177 3675);
DISPLAY INVISIBLE (-3177 3675);
FORCEADD TAP..1
(-3175 3575);
FORCEPROP 3 LASTPIN (-3225 3575) SIG_NAME M_J_CPU0_SA_DQS_DN<3>
J 0
(-3215 3585);
DISPLAY 0.659574 (-3215 3585);
PAINT MONO (-3215 3585);
DISPLAY INVISIBLE (-3215 3585);
FORCEPROP 1 LASTPIN (-3225 3575) BN 3
J 0
(-3237 3583);
DISPLAY 0.489362 (-3237 3583);
PAINT GREEN (-3237 3583);
FORCEPROP 2 LAST CDS_LIB mstr_standard
J 0
(-3175 3575);
DISPLAY 0.723404 (-3175 3575);
PAINT MONO (-3175 3575);
DISPLAY INVISIBLE (-3175 3575);
FORCEPROP 1 LAST BODY_TYPE PLUMBING
J 0
(-3175 3625);
DISPLAY 0.872340 (-3175 3625);
PAINT GREEN (-3175 3625);
DISPLAY INVISIBLE (-3175 3625);
FORCEPROP 1 LAST HDL_TAP TRUE
J 0
(-2850 3450);
DISPLAY 0.872340 (-2850 3450);
DISPLAY INVISIBLE (-2850 3450);
FORCEPROP 1 LAST PATH I204
J 0
(-3177 3575);
DISPLAY 0.872340 (-3177 3575);
PAINT GREEN (-3177 3575);
DISPLAY INVISIBLE (-3177 3575);
FORCEADD TAP..1
(-3175 3475);
FORCEPROP 3 LASTPIN (-3225 3475) SIG_NAME M_J_CPU0_SA_DQS_DN<2>
J 0
(-3215 3485);
DISPLAY 0.659574 (-3215 3485);
PAINT MONO (-3215 3485);
DISPLAY INVISIBLE (-3215 3485);
FORCEPROP 1 LASTPIN (-3225 3475) BN 2
J 0
(-3237 3483);
DISPLAY 0.489362 (-3237 3483);
PAINT GREEN (-3237 3483);
FORCEPROP 2 LAST CDS_LIB mstr_standard
J 0
(-3175 3475);
DISPLAY 0.723404 (-3175 3475);
PAINT MONO (-3175 3475);
DISPLAY INVISIBLE (-3175 3475);
FORCEPROP 1 LAST BODY_TYPE PLUMBING
J 0
(-3175 3525);
DISPLAY 0.872340 (-3175 3525);
PAINT GREEN (-3175 3525);
DISPLAY INVISIBLE (-3175 3525);
FORCEPROP 1 LAST HDL_TAP TRUE
J 0
(-2850 3350);
DISPLAY 0.872340 (-2850 3350);
DISPLAY INVISIBLE (-2850 3350);
FORCEPROP 1 LAST PATH I205
J 0
(-3177 3475);
DISPLAY 0.872340 (-3177 3475);
PAINT GREEN (-3177 3475);
DISPLAY INVISIBLE (-3177 3475);
FORCEADD TAP..1
(-3175 3375);
FORCEPROP 3 LASTPIN (-3225 3375) SIG_NAME M_J_CPU0_SA_DQS_DN<1>
J 0
(-3215 3385);
DISPLAY 0.659574 (-3215 3385);
PAINT MONO (-3215 3385);
DISPLAY INVISIBLE (-3215 3385);
FORCEPROP 1 LASTPIN (-3225 3375) BN 1
J 0
(-3237 3383);
DISPLAY 0.489362 (-3237 3383);
PAINT GREEN (-3237 3383);
FORCEPROP 2 LAST CDS_LIB mstr_standard
J 0
(-3175 3375);
DISPLAY 0.723404 (-3175 3375);
PAINT MONO (-3175 3375);
DISPLAY INVISIBLE (-3175 3375);
FORCEPROP 1 LAST BODY_TYPE PLUMBING
J 0
(-3175 3425);
DISPLAY 0.872340 (-3175 3425);
PAINT GREEN (-3175 3425);
DISPLAY INVISIBLE (-3175 3425);
FORCEPROP 1 LAST HDL_TAP TRUE
J 0
(-2850 3250);
DISPLAY 0.872340 (-2850 3250);
DISPLAY INVISIBLE (-2850 3250);
FORCEPROP 1 LAST PATH I206
J 0
(-3177 3375);
DISPLAY 0.872340 (-3177 3375);
PAINT GREEN (-3177 3375);
DISPLAY INVISIBLE (-3177 3375);
FORCEADD TAP..1
(-3175 3275);
FORCEPROP 3 LASTPIN (-3225 3275) SIG_NAME M_J_CPU0_SA_DQS_DN<0>
J 0
(-3215 3285);
DISPLAY 0.659574 (-3215 3285);
PAINT MONO (-3215 3285);
DISPLAY INVISIBLE (-3215 3285);
FORCEPROP 1 LASTPIN (-3225 3275) BN 0
J 0
(-3237 3283);
DISPLAY 0.489362 (-3237 3283);
PAINT GREEN (-3237 3283);
FORCEPROP 2 LAST CDS_LIB mstr_standard
J 0
(-3175 3275);
DISPLAY 0.723404 (-3175 3275);
PAINT MONO (-3175 3275);
DISPLAY INVISIBLE (-3175 3275);
FORCEPROP 1 LAST BODY_TYPE PLUMBING
J 0
(-3175 3325);
DISPLAY 0.872340 (-3175 3325);
PAINT GREEN (-3175 3325);
DISPLAY INVISIBLE (-3175 3325);
FORCEPROP 1 LAST HDL_TAP TRUE
J 0
(-2850 3150);
DISPLAY 0.872340 (-2850 3150);
DISPLAY INVISIBLE (-2850 3150);
FORCEPROP 1 LAST PATH I207
J 0
(-3177 3275);
DISPLAY 0.872340 (-3177 3275);
PAINT GREEN (-3177 3275);
DISPLAY INVISIBLE (-3177 3275);
FORCEADD TAP..1
(-3175 3125);
FORCEPROP 3 LASTPIN (-3225 3125) SIG_NAME M_J_CPU0_SB_DQS_DN<9>
J 0
(-3215 3135);
DISPLAY 0.659574 (-3215 3135);
PAINT MONO (-3215 3135);
DISPLAY INVISIBLE (-3215 3135);
FORCEPROP 1 LASTPIN (-3225 3125) BN 9
J 0
(-3237 3133);
DISPLAY 0.489362 (-3237 3133);
PAINT GREEN (-3237 3133);
FORCEPROP 2 LAST CDS_LIB mstr_standard
J 0
(-3175 3125);
DISPLAY 0.723404 (-3175 3125);
PAINT MONO (-3175 3125);
DISPLAY INVISIBLE (-3175 3125);
FORCEPROP 1 LAST BODY_TYPE PLUMBING
J 0
(-3175 3175);
DISPLAY 0.872340 (-3175 3175);
PAINT GREEN (-3175 3175);
DISPLAY INVISIBLE (-3175 3175);
FORCEPROP 1 LAST HDL_TAP TRUE
J 0
(-2850 3000);
DISPLAY 0.872340 (-2850 3000);
DISPLAY INVISIBLE (-2850 3000);
FORCEPROP 1 LAST PATH I208
J 0
(-3177 3125);
DISPLAY 0.872340 (-3177 3125);
PAINT GREEN (-3177 3125);
DISPLAY INVISIBLE (-3177 3125);
FORCEADD TAP..1
(-3375 4025);
FORCEPROP 3 LASTPIN (-3425 4025) SIG_NAME M_J_CPU0_SA_DQS_DP<7>
J 0
(-3415 4035);
DISPLAY 0.659574 (-3415 4035);
PAINT MONO (-3415 4035);
DISPLAY INVISIBLE (-3415 4035);
FORCEPROP 1 LASTPIN (-3425 4025) BN 7
J 0
(-3437 4033);
DISPLAY 0.489362 (-3437 4033);
PAINT GREEN (-3437 4033);
FORCEPROP 2 LAST CDS_LIB mstr_standard
J 0
(-3375 4025);
DISPLAY 0.723404 (-3375 4025);
PAINT MONO (-3375 4025);
DISPLAY INVISIBLE (-3375 4025);
FORCEPROP 1 LAST BODY_TYPE PLUMBING
J 0
(-3375 4075);
DISPLAY 0.872340 (-3375 4075);
PAINT GREEN (-3375 4075);
DISPLAY INVISIBLE (-3375 4075);
FORCEPROP 1 LAST HDL_TAP TRUE
J 0
(-3050 3900);
DISPLAY 0.872340 (-3050 3900);
DISPLAY INVISIBLE (-3050 3900);
FORCEPROP 1 LAST PATH I209
J 0
(-3377 4025);
DISPLAY 0.872340 (-3377 4025);
PAINT GREEN (-3377 4025);
DISPLAY INVISIBLE (-3377 4025);
FORCEADD OFFPAGE..1
(-8250 4975);
FORCEPROP 2 LAST $XR0 19 
J 0
(-8501 4975);
DISPLAY 0.638298 (-8501 4975);
PAINT MONO (-8501 4975);
FORCEPROP 2 LAST PATH I21
J 0
(-8200 5050);
DISPLAY 1.021277 (-8200 5050);
DISPLAY INVISIBLE (-8200 5050);
FORCEPROP 1 LAST COMMENT_BODY TRUE
J 0
(-8125 4875);
DISPLAY 0.872340 (-8125 4875);
PAINT GREEN (-8125 4875);
DISPLAY INVISIBLE (-8125 4875);
FORCEPROP 1 LAST OFFPAGE TRUE
J 0
(-7925 4850);
DISPLAY 0.872340 (-7925 4850);
PAINT GREEN (-7925 4850);
DISPLAY INVISIBLE (-7925 4850);
FORCEPROP 2 LAST CDS_LIB mstr_standard
J 0
(-8250 4975);
DISPLAY 0.723404 (-8250 4975);
PAINT MONO (-8250 4975);
DISPLAY INVISIBLE (-8250 4975);
FORCEADD TAP..1
(-3375 3925);
FORCEPROP 3 LASTPIN (-3425 3925) SIG_NAME M_J_CPU0_SA_DQS_DP<6>
J 0
(-3415 3935);
DISPLAY 0.659574 (-3415 3935);
PAINT MONO (-3415 3935);
DISPLAY INVISIBLE (-3415 3935);
FORCEPROP 1 LASTPIN (-3425 3925) BN 6
J 0
(-3437 3933);
DISPLAY 0.489362 (-3437 3933);
PAINT GREEN (-3437 3933);
FORCEPROP 2 LAST CDS_LIB mstr_standard
J 0
(-3375 3925);
DISPLAY 0.723404 (-3375 3925);
PAINT MONO (-3375 3925);
DISPLAY INVISIBLE (-3375 3925);
FORCEPROP 1 LAST BODY_TYPE PLUMBING
J 0
(-3375 3975);
DISPLAY 0.872340 (-3375 3975);
PAINT GREEN (-3375 3975);
DISPLAY INVISIBLE (-3375 3975);
FORCEPROP 1 LAST HDL_TAP TRUE
J 0
(-3050 3800);
DISPLAY 0.872340 (-3050 3800);
DISPLAY INVISIBLE (-3050 3800);
FORCEPROP 1 LAST PATH I210
J 0
(-3377 3925);
DISPLAY 0.872340 (-3377 3925);
PAINT GREEN (-3377 3925);
DISPLAY INVISIBLE (-3377 3925);
FORCEADD TAP..1
(-3375 3825);
FORCEPROP 3 LASTPIN (-3425 3825) SIG_NAME M_J_CPU0_SA_DQS_DP<5>
J 0
(-3415 3835);
DISPLAY 0.659574 (-3415 3835);
PAINT MONO (-3415 3835);
DISPLAY INVISIBLE (-3415 3835);
FORCEPROP 1 LASTPIN (-3425 3825) BN 5
J 0
(-3437 3833);
DISPLAY 0.489362 (-3437 3833);
PAINT GREEN (-3437 3833);
FORCEPROP 2 LAST CDS_LIB mstr_standard
J 0
(-3375 3825);
DISPLAY 0.723404 (-3375 3825);
PAINT MONO (-3375 3825);
DISPLAY INVISIBLE (-3375 3825);
FORCEPROP 1 LAST BODY_TYPE PLUMBING
J 0
(-3375 3875);
DISPLAY 0.872340 (-3375 3875);
PAINT GREEN (-3375 3875);
DISPLAY INVISIBLE (-3375 3875);
FORCEPROP 1 LAST HDL_TAP TRUE
J 0
(-3050 3700);
DISPLAY 0.872340 (-3050 3700);
DISPLAY INVISIBLE (-3050 3700);
FORCEPROP 1 LAST PATH I211
J 0
(-3377 3825);
DISPLAY 0.872340 (-3377 3825);
PAINT GREEN (-3377 3825);
DISPLAY INVISIBLE (-3377 3825);
FORCEADD TAP..1
(-3375 3725);
FORCEPROP 3 LASTPIN (-3425 3725) SIG_NAME M_J_CPU0_SA_DQS_DP<4>
J 0
(-3415 3735);
DISPLAY 0.659574 (-3415 3735);
PAINT MONO (-3415 3735);
DISPLAY INVISIBLE (-3415 3735);
FORCEPROP 1 LASTPIN (-3425 3725) BN 4
J 0
(-3437 3733);
DISPLAY 0.489362 (-3437 3733);
PAINT GREEN (-3437 3733);
FORCEPROP 2 LAST CDS_LIB mstr_standard
J 0
(-3375 3725);
DISPLAY 0.723404 (-3375 3725);
PAINT MONO (-3375 3725);
DISPLAY INVISIBLE (-3375 3725);
FORCEPROP 1 LAST BODY_TYPE PLUMBING
J 0
(-3375 3775);
DISPLAY 0.872340 (-3375 3775);
PAINT GREEN (-3375 3775);
DISPLAY INVISIBLE (-3375 3775);
FORCEPROP 1 LAST HDL_TAP TRUE
J 0
(-3050 3600);
DISPLAY 0.872340 (-3050 3600);
DISPLAY INVISIBLE (-3050 3600);
FORCEPROP 1 LAST PATH I212
J 0
(-3377 3725);
DISPLAY 0.872340 (-3377 3725);
PAINT GREEN (-3377 3725);
DISPLAY INVISIBLE (-3377 3725);
FORCEADD TAP..1
(-3375 3625);
FORCEPROP 3 LASTPIN (-3425 3625) SIG_NAME M_J_CPU0_SA_DQS_DP<3>
J 0
(-3415 3635);
DISPLAY 0.659574 (-3415 3635);
PAINT MONO (-3415 3635);
DISPLAY INVISIBLE (-3415 3635);
FORCEPROP 1 LASTPIN (-3425 3625) BN 3
J 0
(-3437 3633);
DISPLAY 0.489362 (-3437 3633);
PAINT GREEN (-3437 3633);
FORCEPROP 2 LAST CDS_LIB mstr_standard
J 0
(-3375 3625);
DISPLAY 0.723404 (-3375 3625);
PAINT MONO (-3375 3625);
DISPLAY INVISIBLE (-3375 3625);
FORCEPROP 1 LAST BODY_TYPE PLUMBING
J 0
(-3375 3675);
DISPLAY 0.872340 (-3375 3675);
PAINT GREEN (-3375 3675);
DISPLAY INVISIBLE (-3375 3675);
FORCEPROP 1 LAST HDL_TAP TRUE
J 0
(-3050 3500);
DISPLAY 0.872340 (-3050 3500);
DISPLAY INVISIBLE (-3050 3500);
FORCEPROP 1 LAST PATH I213
J 0
(-3377 3625);
DISPLAY 0.872340 (-3377 3625);
PAINT GREEN (-3377 3625);
DISPLAY INVISIBLE (-3377 3625);
FORCEADD TAP..1
(-3375 3525);
FORCEPROP 3 LASTPIN (-3425 3525) SIG_NAME M_J_CPU0_SA_DQS_DP<2>
J 0
(-3415 3535);
DISPLAY 0.659574 (-3415 3535);
PAINT MONO (-3415 3535);
DISPLAY INVISIBLE (-3415 3535);
FORCEPROP 1 LASTPIN (-3425 3525) BN 2
J 0
(-3437 3533);
DISPLAY 0.489362 (-3437 3533);
PAINT GREEN (-3437 3533);
FORCEPROP 2 LAST CDS_LIB mstr_standard
J 0
(-3375 3525);
DISPLAY 0.723404 (-3375 3525);
PAINT MONO (-3375 3525);
DISPLAY INVISIBLE (-3375 3525);
FORCEPROP 1 LAST BODY_TYPE PLUMBING
J 0
(-3375 3575);
DISPLAY 0.872340 (-3375 3575);
PAINT GREEN (-3375 3575);
DISPLAY INVISIBLE (-3375 3575);
FORCEPROP 1 LAST HDL_TAP TRUE
J 0
(-3050 3400);
DISPLAY 0.872340 (-3050 3400);
DISPLAY INVISIBLE (-3050 3400);
FORCEPROP 1 LAST PATH I214
J 0
(-3377 3525);
DISPLAY 0.872340 (-3377 3525);
PAINT GREEN (-3377 3525);
DISPLAY INVISIBLE (-3377 3525);
FORCEADD TAP..1
(-3375 3425);
FORCEPROP 3 LASTPIN (-3425 3425) SIG_NAME M_J_CPU0_SA_DQS_DP<1>
J 0
(-3415 3435);
DISPLAY 0.659574 (-3415 3435);
PAINT MONO (-3415 3435);
DISPLAY INVISIBLE (-3415 3435);
FORCEPROP 1 LASTPIN (-3425 3425) BN 1
J 0
(-3437 3433);
DISPLAY 0.489362 (-3437 3433);
PAINT GREEN (-3437 3433);
FORCEPROP 2 LAST CDS_LIB mstr_standard
J 0
(-3375 3425);
DISPLAY 0.723404 (-3375 3425);
PAINT MONO (-3375 3425);
DISPLAY INVISIBLE (-3375 3425);
FORCEPROP 1 LAST BODY_TYPE PLUMBING
J 0
(-3375 3475);
DISPLAY 0.872340 (-3375 3475);
PAINT GREEN (-3375 3475);
DISPLAY INVISIBLE (-3375 3475);
FORCEPROP 1 LAST HDL_TAP TRUE
J 0
(-3050 3300);
DISPLAY 0.872340 (-3050 3300);
DISPLAY INVISIBLE (-3050 3300);
FORCEPROP 1 LAST PATH I215
J 0
(-3377 3425);
DISPLAY 0.872340 (-3377 3425);
PAINT GREEN (-3377 3425);
DISPLAY INVISIBLE (-3377 3425);
FORCEADD TAP..1
(-3375 3325);
FORCEPROP 3 LASTPIN (-3425 3325) SIG_NAME M_J_CPU0_SA_DQS_DP<0>
J 0
(-3415 3335);
DISPLAY 0.659574 (-3415 3335);
PAINT MONO (-3415 3335);
DISPLAY INVISIBLE (-3415 3335);
FORCEPROP 1 LASTPIN (-3425 3325) BN 0
J 0
(-3437 3333);
DISPLAY 0.489362 (-3437 3333);
PAINT GREEN (-3437 3333);
FORCEPROP 2 LAST CDS_LIB mstr_standard
J 0
(-3375 3325);
DISPLAY 0.723404 (-3375 3325);
PAINT MONO (-3375 3325);
DISPLAY INVISIBLE (-3375 3325);
FORCEPROP 1 LAST BODY_TYPE PLUMBING
J 0
(-3375 3375);
DISPLAY 0.872340 (-3375 3375);
PAINT GREEN (-3375 3375);
DISPLAY INVISIBLE (-3375 3375);
FORCEPROP 1 LAST HDL_TAP TRUE
J 0
(-3050 3200);
DISPLAY 0.872340 (-3050 3200);
DISPLAY INVISIBLE (-3050 3200);
FORCEPROP 1 LAST PATH I216
J 0
(-3377 3325);
DISPLAY 0.872340 (-3377 3325);
PAINT GREEN (-3377 3325);
DISPLAY INVISIBLE (-3377 3325);
FORCEADD TAP..1
(-3375 3175);
FORCEPROP 3 LASTPIN (-3425 3175) SIG_NAME M_J_CPU0_SB_DQS_DP<9>
J 0
(-3415 3185);
DISPLAY 0.659574 (-3415 3185);
PAINT MONO (-3415 3185);
DISPLAY INVISIBLE (-3415 3185);
FORCEPROP 1 LASTPIN (-3425 3175) BN 9
J 0
(-3437 3183);
DISPLAY 0.489362 (-3437 3183);
PAINT GREEN (-3437 3183);
FORCEPROP 2 LAST CDS_LIB mstr_standard
J 0
(-3375 3175);
DISPLAY 0.723404 (-3375 3175);
PAINT MONO (-3375 3175);
DISPLAY INVISIBLE (-3375 3175);
FORCEPROP 1 LAST BODY_TYPE PLUMBING
J 0
(-3375 3225);
DISPLAY 0.872340 (-3375 3225);
PAINT GREEN (-3375 3225);
DISPLAY INVISIBLE (-3375 3225);
FORCEPROP 1 LAST HDL_TAP TRUE
J 0
(-3050 3050);
DISPLAY 0.872340 (-3050 3050);
DISPLAY INVISIBLE (-3050 3050);
FORCEPROP 1 LAST PATH I217
J 0
(-3377 3175);
DISPLAY 0.872340 (-3377 3175);
PAINT GREEN (-3377 3175);
DISPLAY INVISIBLE (-3377 3175);
FORCEADD TAP..1
(-3375 3075);
FORCEPROP 3 LASTPIN (-3425 3075) SIG_NAME M_J_CPU0_SB_DQS_DP<8>
J 0
(-3415 3085);
DISPLAY 0.659574 (-3415 3085);
PAINT MONO (-3415 3085);
DISPLAY INVISIBLE (-3415 3085);
FORCEPROP 1 LASTPIN (-3425 3075) BN 8
J 0
(-3437 3083);
DISPLAY 0.489362 (-3437 3083);
PAINT GREEN (-3437 3083);
FORCEPROP 2 LAST CDS_LIB mstr_standard
J 0
(-3375 3075);
DISPLAY 0.723404 (-3375 3075);
PAINT MONO (-3375 3075);
DISPLAY INVISIBLE (-3375 3075);
FORCEPROP 1 LAST BODY_TYPE PLUMBING
J 0
(-3375 3125);
DISPLAY 0.872340 (-3375 3125);
PAINT GREEN (-3375 3125);
DISPLAY INVISIBLE (-3375 3125);
FORCEPROP 1 LAST HDL_TAP TRUE
J 0
(-3050 2950);
DISPLAY 0.872340 (-3050 2950);
DISPLAY INVISIBLE (-3050 2950);
FORCEPROP 1 LAST PATH I218
J 0
(-3377 3075);
DISPLAY 0.872340 (-3377 3075);
PAINT GREEN (-3377 3075);
DISPLAY INVISIBLE (-3377 3075);
FORCEADD TAP..1
(-3175 2925);
FORCEPROP 3 LASTPIN (-3225 2925) SIG_NAME M_J_CPU0_SB_DQS_DN<7>
J 0
(-3215 2935);
DISPLAY 0.659574 (-3215 2935);
PAINT MONO (-3215 2935);
DISPLAY INVISIBLE (-3215 2935);
FORCEPROP 1 LASTPIN (-3225 2925) BN 7
J 0
(-3237 2933);
DISPLAY 0.489362 (-3237 2933);
PAINT GREEN (-3237 2933);
FORCEPROP 2 LAST CDS_LIB mstr_standard
J 0
(-3175 2925);
DISPLAY 0.723404 (-3175 2925);
PAINT MONO (-3175 2925);
DISPLAY INVISIBLE (-3175 2925);
FORCEPROP 1 LAST BODY_TYPE PLUMBING
J 0
(-3175 2975);
DISPLAY 0.872340 (-3175 2975);
PAINT GREEN (-3175 2975);
DISPLAY INVISIBLE (-3175 2975);
FORCEPROP 1 LAST HDL_TAP TRUE
J 0
(-2850 2800);
DISPLAY 0.872340 (-2850 2800);
DISPLAY INVISIBLE (-2850 2800);
FORCEPROP 1 LAST PATH I219
J 0
(-3177 2925);
DISPLAY 0.872340 (-3177 2925);
PAINT GREEN (-3177 2925);
DISPLAY INVISIBLE (-3177 2925);
FORCEADD SCONN288_DDR506112002KQ..1
(-6800 3575);
FORCEPROP 1 LAST LOCATION J68
J 0
(-7250 5650);
DISPLAY 0.468085 (-7250 5650);
PAINT SKYBLUE (-7250 5650);
FORCEPROP 0 LAST $SEC 1
J 0
(-7250 5800);
DISPLAY 0.680851 (-7250 5800);
PAINT MONO (-7250 5800);
DISPLAY INVISIBLE (-7250 5800);
FORCEPROP 2 LAST CDS_SEC 1
J 0
(-7250 5800);
DISPLAY 1.021277 (-7250 5800);
DISPLAY INVISIBLE (-7250 5800);
FORCEPROP 0 LASTPIN (-7400 2975) $PN 62
J 2
(-7410 2985);
DISPLAY 0.680851 (-7410 2985);
PAINT MONO (-7410 2985);
FORCEPROP 0 LASTPIN (-7400 5025) $PN 66
J 2
(-7410 5035);
DISPLAY 0.680851 (-7410 5035);
PAINT MONO (-7410 5035);
FORCEPROP 0 LASTPIN (-7400 4625) $PN 76
J 2
(-7410 4635);
DISPLAY 0.680851 (-7410 4635);
PAINT MONO (-7410 4635);
FORCEPROP 0 LASTPIN (-7400 5075) $PN 211
J 2
(-7410 5085);
DISPLAY 0.680851 (-7410 5085);
PAINT MONO (-7410 5085);
FORCEPROP 0 LASTPIN (-7400 4675) $PN 221
J 2
(-7410 4685);
DISPLAY 0.680851 (-7410 4685);
PAINT MONO (-7410 4685);
FORCEPROP 0 LASTPIN (-7400 5125) $PN 68
J 2
(-7410 5135);
DISPLAY 0.680851 (-7410 5135);
PAINT MONO (-7410 5135);
FORCEPROP 0 LASTPIN (-7400 4725) $PN 78
J 2
(-7410 4735);
DISPLAY 0.680851 (-7410 4735);
PAINT MONO (-7410 4735);
FORCEPROP 0 LASTPIN (-7400 5175) $PN 213
J 2
(-7410 5185);
DISPLAY 0.680851 (-7410 5185);
PAINT MONO (-7410 5185);
FORCEPROP 0 LASTPIN (-7400 4775) $PN 223
J 2
(-7410 4785);
DISPLAY 0.680851 (-7410 4785);
PAINT MONO (-7410 4785);
FORCEPROP 0 LASTPIN (-7400 5225) $PN 70
J 2
(-7410 5235);
DISPLAY 0.680851 (-7410 5235);
PAINT MONO (-7410 5235);
FORCEPROP 0 LASTPIN (-7400 4825) $PN 80
J 2
(-7410 4835);
DISPLAY 0.680851 (-7410 4835);
PAINT MONO (-7410 4835);
FORCEPROP 0 LASTPIN (-7400 5275) $PN 215
J 2
(-7410 5285);
DISPLAY 0.680851 (-7410 5285);
PAINT MONO (-7410 5285);
FORCEPROP 0 LASTPIN (-7400 4875) $PN 225
J 2
(-7410 4885);
DISPLAY 0.680851 (-7410 4885);
PAINT MONO (-7410 4885);
FORCEPROP 0 LASTPIN (-7400 5325) $PN 72
J 2
(-7410 5335);
DISPLAY 0.680851 (-7410 5335);
PAINT MONO (-7410 5335);
FORCEPROP 0 LASTPIN (-7400 4925) $PN 82
J 2
(-7410 4935);
DISPLAY 0.680851 (-7410 4935);
PAINT MONO (-7410 4935);
FORCEPROP 0 LASTPIN (-7400 3575) $PN 51
J 2
(-7410 3585);
DISPLAY 0.680851 (-7410 3585);
PAINT MONO (-7410 3585);
FORCEPROP 0 LASTPIN (-7400 3125) $PN 96
J 2
(-7410 3135);
DISPLAY 0.680851 (-7410 3135);
PAINT MONO (-7410 3135);
FORCEPROP 0 LASTPIN (-7400 3625) $PN 53
J 2
(-7410 3635);
DISPLAY 0.680851 (-7410 3635);
PAINT MONO (-7410 3635);
FORCEPROP 0 LASTPIN (-7400 3175) $PN 98
J 2
(-7410 3185);
DISPLAY 0.680851 (-7410 3185);
PAINT MONO (-7410 3185);
FORCEPROP 0 LASTPIN (-7400 3675) $PN 196
J 2
(-7410 3685);
DISPLAY 0.680851 (-7410 3685);
PAINT MONO (-7410 3685);
FORCEPROP 0 LASTPIN (-7400 3225) $PN 241
J 2
(-7410 3235);
DISPLAY 0.680851 (-7410 3235);
PAINT MONO (-7410 3235);
FORCEPROP 0 LASTPIN (-7400 3725) $PN 198
J 2
(-7410 3735);
DISPLAY 0.680851 (-7410 3735);
PAINT MONO (-7410 3735);
FORCEPROP 0 LASTPIN (-7400 3275) $PN 243
J 2
(-7410 3285);
DISPLAY 0.680851 (-7410 3285);
PAINT MONO (-7410 3285);
FORCEPROP 0 LASTPIN (-7400 3775) $PN 58
J 2
(-7410 3785);
DISPLAY 0.680851 (-7410 3785);
PAINT MONO (-7410 3785);
FORCEPROP 0 LASTPIN (-7400 3325) $PN 89
J 2
(-7410 3335);
DISPLAY 0.680851 (-7410 3335);
PAINT MONO (-7410 3335);
FORCEPROP 0 LASTPIN (-7400 3825) $PN 60
J 2
(-7410 3835);
DISPLAY 0.680851 (-7410 3835);
PAINT MONO (-7410 3835);
FORCEPROP 0 LASTPIN (-7400 3375) $PN 91
J 2
(-7410 3385);
DISPLAY 0.680851 (-7410 3385);
PAINT MONO (-7410 3385);
FORCEPROP 0 LASTPIN (-7400 3875) $PN 203
J 2
(-7410 3885);
DISPLAY 0.680851 (-7410 3885);
PAINT MONO (-7410 3885);
FORCEPROP 0 LASTPIN (-7400 3425) $PN 234
J 2
(-7410 3435);
DISPLAY 0.680851 (-7410 3435);
PAINT MONO (-7410 3435);
FORCEPROP 0 LASTPIN (-7400 3925) $PN 205
J 2
(-7410 3935);
DISPLAY 0.680851 (-7410 3935);
PAINT MONO (-7410 3935);
FORCEPROP 0 LASTPIN (-7400 3475) $PN 236
J 2
(-7410 3485);
DISPLAY 0.680851 (-7410 3485);
PAINT MONO (-7410 3485);
FORCEPROP 0 LASTPIN (-7400 4025) $PN 218
J 2
(-7410 4035);
DISPLAY 0.680851 (-7410 4035);
PAINT MONO (-7410 4035);
FORCEPROP 0 LASTPIN (-7400 4075) $PN 217
J 2
(-7410 4085);
DISPLAY 0.680851 (-7410 4085);
PAINT MONO (-7410 4085);
FORCEPROP 0 LASTPIN (-7400 4325) $PN 64
J 2
(-7410 4335);
DISPLAY 0.680851 (-7410 4335);
PAINT MONO (-7410 4335);
FORCEPROP 0 LASTPIN (-7400 4175) $PN 84
J 2
(-7410 4185);
DISPLAY 0.680851 (-7410 4185);
PAINT MONO (-7410 4185);
FORCEPROP 0 LASTPIN (-7400 4375) $PN 209
J 2
(-7410 4385);
DISPLAY 0.680851 (-7410 4385);
PAINT MONO (-7410 4385);
FORCEPROP 0 LASTPIN (-7400 4225) $PN 229
J 2
(-7410 4235);
DISPLAY 0.680851 (-7410 4235);
PAINT MONO (-7410 4235);
FORCEPROP 0 LASTPIN (-6200 3775) $PN 7
J 0
(-6190 3785);
DISPLAY 0.680851 (-6190 3785);
PAINT MONO (-6190 3785);
FORCEPROP 0 LASTPIN (-6200 2125) $PN 100
J 0
(-6190 2135);
DISPLAY 0.680851 (-6190 2135);
PAINT MONO (-6190 2135);
FORCEPROP 0 LASTPIN (-6200 3825) $PN 9
J 0
(-6190 3835);
DISPLAY 0.680851 (-6190 3835);
PAINT MONO (-6190 3835);
FORCEPROP 0 LASTPIN (-6200 2175) $PN 102
J 0
(-6190 2185);
DISPLAY 0.680851 (-6190 2185);
PAINT MONO (-6190 2185);
FORCEPROP 0 LASTPIN (-6200 3875) $PN 152
J 0
(-6190 3885);
DISPLAY 0.680851 (-6190 3885);
PAINT MONO (-6190 3885);
FORCEPROP 0 LASTPIN (-6200 2225) $PN 245
J 0
(-6190 2235);
DISPLAY 0.680851 (-6190 2235);
PAINT MONO (-6190 2235);
FORCEPROP 0 LASTPIN (-6200 3925) $PN 154
J 0
(-6190 3935);
DISPLAY 0.680851 (-6190 3935);
PAINT MONO (-6190 3935);
FORCEPROP 0 LASTPIN (-6200 2275) $PN 247
J 0
(-6190 2285);
DISPLAY 0.680851 (-6190 2285);
PAINT MONO (-6190 2285);
FORCEPROP 0 LASTPIN (-6200 3975) $PN 14
J 0
(-6190 3985);
DISPLAY 0.680851 (-6190 3985);
PAINT MONO (-6190 3985);
FORCEPROP 0 LASTPIN (-6200 2325) $PN 107
J 0
(-6190 2335);
DISPLAY 0.680851 (-6190 2335);
PAINT MONO (-6190 2335);
FORCEPROP 0 LASTPIN (-6200 4025) $PN 16
J 0
(-6190 4035);
DISPLAY 0.680851 (-6190 4035);
PAINT MONO (-6190 4035);
FORCEPROP 0 LASTPIN (-6200 2375) $PN 109
J 0
(-6190 2385);
DISPLAY 0.680851 (-6190 2385);
PAINT MONO (-6190 2385);
FORCEPROP 0 LASTPIN (-6200 4075) $PN 159
J 0
(-6190 4085);
DISPLAY 0.680851 (-6190 4085);
PAINT MONO (-6190 4085);
FORCEPROP 0 LASTPIN (-6200 2425) $PN 252
J 0
(-6190 2435);
DISPLAY 0.680851 (-6190 2435);
PAINT MONO (-6190 2435);
FORCEPROP 0 LASTPIN (-6200 4125) $PN 161
J 0
(-6190 4135);
DISPLAY 0.680851 (-6190 4135);
PAINT MONO (-6190 4135);
FORCEPROP 0 LASTPIN (-6200 2475) $PN 254
J 0
(-6190 2485);
DISPLAY 0.680851 (-6190 2485);
PAINT MONO (-6190 2485);
FORCEPROP 0 LASTPIN (-6200 4175) $PN 18
J 0
(-6190 4185);
DISPLAY 0.680851 (-6190 4185);
PAINT MONO (-6190 4185);
FORCEPROP 0 LASTPIN (-6200 2525) $PN 111
J 0
(-6190 2535);
DISPLAY 0.680851 (-6190 2535);
PAINT MONO (-6190 2535);
FORCEPROP 0 LASTPIN (-6200 4225) $PN 20
J 0
(-6190 4235);
DISPLAY 0.680851 (-6190 4235);
PAINT MONO (-6190 4235);
FORCEPROP 0 LASTPIN (-6200 2575) $PN 113
J 0
(-6190 2585);
DISPLAY 0.680851 (-6190 2585);
PAINT MONO (-6190 2585);
FORCEPROP 0 LASTPIN (-6200 4275) $PN 163
J 0
(-6190 4285);
DISPLAY 0.680851 (-6190 4285);
PAINT MONO (-6190 4285);
FORCEPROP 0 LASTPIN (-6200 2625) $PN 256
J 0
(-6190 2635);
DISPLAY 0.680851 (-6190 2635);
PAINT MONO (-6190 2635);
FORCEPROP 0 LASTPIN (-6200 4325) $PN 165
J 0
(-6190 4335);
DISPLAY 0.680851 (-6190 4335);
PAINT MONO (-6190 4335);
FORCEPROP 0 LASTPIN (-6200 2675) $PN 258
J 0
(-6190 2685);
DISPLAY 0.680851 (-6190 2685);
PAINT MONO (-6190 2685);
FORCEPROP 0 LASTPIN (-6200 4375) $PN 25
J 0
(-6190 4385);
DISPLAY 0.680851 (-6190 4385);
PAINT MONO (-6190 4385);
FORCEPROP 0 LASTPIN (-6200 2725) $PN 118
J 0
(-6190 2735);
DISPLAY 0.680851 (-6190 2735);
PAINT MONO (-6190 2735);
FORCEPROP 0 LASTPIN (-6200 4425) $PN 27
J 0
(-6190 4435);
DISPLAY 0.680851 (-6190 4435);
PAINT MONO (-6190 4435);
FORCEPROP 0 LASTPIN (-6200 2775) $PN 120
J 0
(-6190 2785);
DISPLAY 0.680851 (-6190 2785);
PAINT MONO (-6190 2785);
FORCEPROP 0 LASTPIN (-6200 4475) $PN 170
J 0
(-6190 4485);
DISPLAY 0.680851 (-6190 4485);
PAINT MONO (-6190 4485);
FORCEPROP 0 LASTPIN (-6200 2825) $PN 263
J 0
(-6190 2835);
DISPLAY 0.680851 (-6190 2835);
PAINT MONO (-6190 2835);
FORCEPROP 0 LASTPIN (-6200 4525) $PN 172
J 0
(-6190 4535);
DISPLAY 0.680851 (-6190 4535);
PAINT MONO (-6190 4535);
FORCEPROP 0 LASTPIN (-6200 2875) $PN 265
J 0
(-6190 2885);
DISPLAY 0.680851 (-6190 2885);
PAINT MONO (-6190 2885);
FORCEPROP 0 LASTPIN (-6200 4575) $PN 29
J 0
(-6190 4585);
DISPLAY 0.680851 (-6190 4585);
PAINT MONO (-6190 4585);
FORCEPROP 0 LASTPIN (-6200 2925) $PN 122
J 0
(-6190 2935);
DISPLAY 0.680851 (-6190 2935);
PAINT MONO (-6190 2935);
FORCEPROP 0 LASTPIN (-6200 4625) $PN 31
J 0
(-6190 4635);
DISPLAY 0.680851 (-6190 4635);
PAINT MONO (-6190 4635);
FORCEPROP 0 LASTPIN (-6200 2975) $PN 124
J 0
(-6190 2985);
DISPLAY 0.680851 (-6190 2985);
PAINT MONO (-6190 2985);
FORCEPROP 0 LASTPIN (-6200 4675) $PN 174
J 0
(-6190 4685);
DISPLAY 0.680851 (-6190 4685);
PAINT MONO (-6190 4685);
FORCEPROP 0 LASTPIN (-6200 3025) $PN 267
J 0
(-6190 3035);
DISPLAY 0.680851 (-6190 3035);
PAINT MONO (-6190 3035);
FORCEPROP 0 LASTPIN (-6200 4725) $PN 176
J 0
(-6190 4735);
DISPLAY 0.680851 (-6190 4735);
PAINT MONO (-6190 4735);
FORCEPROP 0 LASTPIN (-6200 3075) $PN 269
J 0
(-6190 3085);
DISPLAY 0.680851 (-6190 3085);
PAINT MONO (-6190 3085);
FORCEPROP 0 LASTPIN (-6200 4775) $PN 36
J 0
(-6190 4785);
DISPLAY 0.680851 (-6190 4785);
PAINT MONO (-6190 4785);
FORCEPROP 0 LASTPIN (-6200 3125) $PN 129
J 0
(-6190 3135);
DISPLAY 0.680851 (-6190 3135);
PAINT MONO (-6190 3135);
FORCEPROP 0 LASTPIN (-6200 4825) $PN 38
J 0
(-6190 4835);
DISPLAY 0.680851 (-6190 4835);
PAINT MONO (-6190 4835);
FORCEPROP 0 LASTPIN (-6200 3175) $PN 131
J 0
(-6190 3185);
DISPLAY 0.680851 (-6190 3185);
PAINT MONO (-6190 3185);
FORCEPROP 0 LASTPIN (-6200 4875) $PN 181
J 0
(-6190 4885);
DISPLAY 0.680851 (-6190 4885);
PAINT MONO (-6190 4885);
FORCEPROP 0 LASTPIN (-6200 3225) $PN 274
J 0
(-6190 3235);
DISPLAY 0.680851 (-6190 3235);
PAINT MONO (-6190 3235);
FORCEPROP 0 LASTPIN (-6200 4925) $PN 183
J 0
(-6190 4935);
DISPLAY 0.680851 (-6190 4935);
PAINT MONO (-6190 4935);
FORCEPROP 0 LASTPIN (-6200 3275) $PN 276
J 0
(-6190 3285);
DISPLAY 0.680851 (-6190 3285);
PAINT MONO (-6190 3285);
FORCEPROP 0 LASTPIN (-6200 4975) $PN 40
J 0
(-6190 4985);
DISPLAY 0.680851 (-6190 4985);
PAINT MONO (-6190 4985);
FORCEPROP 0 LASTPIN (-6200 3325) $PN 133
J 0
(-6190 3335);
DISPLAY 0.680851 (-6190 3335);
PAINT MONO (-6190 3335);
FORCEPROP 0 LASTPIN (-6200 5025) $PN 42
J 0
(-6190 5035);
DISPLAY 0.680851 (-6190 5035);
PAINT MONO (-6190 5035);
FORCEPROP 0 LASTPIN (-6200 3375) $PN 135
J 0
(-6190 3385);
DISPLAY 0.680851 (-6190 3385);
PAINT MONO (-6190 3385);
FORCEPROP 0 LASTPIN (-6200 5075) $PN 185
J 0
(-6190 5085);
DISPLAY 0.680851 (-6190 5085);
PAINT MONO (-6190 5085);
FORCEPROP 0 LASTPIN (-6200 3425) $PN 278
J 0
(-6190 3435);
DISPLAY 0.680851 (-6190 3435);
PAINT MONO (-6190 3435);
FORCEPROP 0 LASTPIN (-6200 5125) $PN 187
J 0
(-6190 5135);
DISPLAY 0.680851 (-6190 5135);
PAINT MONO (-6190 5135);
FORCEPROP 0 LASTPIN (-6200 3475) $PN 280
J 0
(-6190 3485);
DISPLAY 0.680851 (-6190 3485);
PAINT MONO (-6190 3485);
FORCEPROP 0 LASTPIN (-6200 5175) $PN 47
J 0
(-6190 5185);
DISPLAY 0.680851 (-6190 5185);
PAINT MONO (-6190 5185);
FORCEPROP 0 LASTPIN (-6200 3525) $PN 140
J 0
(-6190 3535);
DISPLAY 0.680851 (-6190 3535);
PAINT MONO (-6190 3535);
FORCEPROP 0 LASTPIN (-6200 5225) $PN 49
J 0
(-6190 5235);
DISPLAY 0.680851 (-6190 5235);
PAINT MONO (-6190 5235);
FORCEPROP 0 LASTPIN (-6200 3575) $PN 142
J 0
(-6190 3585);
DISPLAY 0.680851 (-6190 3585);
PAINT MONO (-6190 3585);
FORCEPROP 0 LASTPIN (-6200 5275) $PN 192
J 0
(-6190 5285);
DISPLAY 0.680851 (-6190 5285);
PAINT MONO (-6190 5285);
FORCEPROP 0 LASTPIN (-6200 3625) $PN 285
J 0
(-6190 3635);
DISPLAY 0.680851 (-6190 3635);
PAINT MONO (-6190 3635);
FORCEPROP 0 LASTPIN (-6200 5325) $PN 194
J 0
(-6190 5335);
DISPLAY 0.680851 (-6190 5335);
PAINT MONO (-6190 5335);
FORCEPROP 0 LASTPIN (-6200 3675) $PN 287
J 0
(-6190 3685);
DISPLAY 0.680851 (-6190 3685);
PAINT MONO (-6190 3685);
FORCEPROP 0 LASTPIN (-7400 2825) $PN 148
J 2
(-7410 2835);
DISPLAY 0.680851 (-7410 2835);
PAINT MONO (-7410 2835);
FORCEPROP 0 LASTPIN (-7400 2725) $PN 4
J 2
(-7410 2735);
DISPLAY 0.680851 (-7410 2735);
PAINT MONO (-7410 2735);
FORCEPROP 0 LASTPIN (-7400 2775) $PN 5
J 2
(-7410 2785);
DISPLAY 0.680851 (-7410 2785);
PAINT MONO (-7410 2785);
FORCEPROP 0 LASTPIN (-7400 1925) $PN 86
J 2
(-7410 1935);
DISPLAY 0.680851 (-7410 1935);
PAINT MONO (-7410 1935);
FORCEPROP 0 LASTPIN (-7400 1875) $PN 87
J 2
(-7410 1885);
DISPLAY 0.680851 (-7410 1885);
PAINT MONO (-7410 1885);
FORCEPROP 0 LASTPIN (-7400 4525) $PN 74
J 2
(-7410 4535);
DISPLAY 0.680851 (-7410 4535);
PAINT MONO (-7410 4535);
FORCEPROP 0 LASTPIN (-7400 4475) $PN 227
J 2
(-7410 4485);
DISPLAY 0.680851 (-7410 4485);
PAINT MONO (-7410 4485);
FORCEPROP 0 LASTPIN (-7400 2475) $PN 147
J 2
(-7410 2485);
DISPLAY 0.680851 (-7410 2485);
PAINT MONO (-7410 2485);
FORCEPROP 0 LASTPIN (-7400 3025) $PN 207
J 2
(-7410 3035);
DISPLAY 0.680851 (-7410 3035);
PAINT MONO (-7410 3035);
FORCEPROP 0 LASTPIN (-7400 2075) $PN 2
J 2
(-7410 2085);
DISPLAY 0.680851 (-7410 2085);
PAINT MONO (-7410 2085);
FORCEPROP 0 LASTPIN (-7400 2125) $PN 144
J 2
(-7410 2135);
DISPLAY 0.680851 (-7410 2135);
PAINT MONO (-7410 2135);
FORCEPROP 0 LASTPIN (-7400 2175) $PN 149
J 2
(-7410 2185);
DISPLAY 0.680851 (-7410 2185);
PAINT MONO (-7410 2185);
FORCEPROP 0 LASTPIN (-7400 2225) $PN 150
J 2
(-7410 2235);
DISPLAY 0.680851 (-7410 2235);
PAINT MONO (-7410 2235);
FORCEPROP 0 LASTPIN (-7400 2275) $PN 220
J 2
(-7410 2285);
DISPLAY 0.680851 (-7410 2285);
PAINT MONO (-7410 2285);
FORCEPROP 0 LASTPIN (-7400 2325) $PN 231
J 2
(-7410 2335);
DISPLAY 0.680851 (-7410 2335);
PAINT MONO (-7410 2335);
FORCEPROP 0 LASTPIN (-7400 2375) $PN 232
J 2
(-7410 2385);
DISPLAY 0.680851 (-7410 2385);
PAINT MONO (-7410 2385);
FORCEPROP 0 LASTPIN (-7400 2875) $PN 3
J 2
(-7410 2885);
DISPLAY 0.680851 (-7410 2885);
PAINT MONO (-7410 2885);
FORCEPROP 1 LAST MATERIAL IO
J 0
(-7250 5500);
DISPLAY 0.468085 (-7250 5500);
PAINT SKYBLUE (-7250 5500);
FORCEPROP 1 LAST PART_NUMBER DFHST8FS479
J 0
(-7250 5575);
DISPLAY 0.468085 (-7250 5575);
PAINT SKYBLUE (-7250 5575);
FORCEPROP 2 LAST VALUE SCONN288_DDR506112002KQ
J 0
(-7250 5700);
DISPLAY 0.489362 (-7250 5700);
PAINT SKYBLUE (-7250 5700);
FORCEPROP 2 LAST PART_TYPE SMLF
J 0
(-7250 5750);
DISPLAY 1.021277 (-7250 5750);
FORCEPROP 1 LAST CDS_LMAN_SYM_OUTLINE -450,1900,450,-1850
J 0
(-6800 3575);
DISPLAY 0.468085 (-6800 3575);
PAINT GREEN (-6800 3575);
DISPLAY INVISIBLE (-6800 3575);
FORCEPROP 1 LAST PATH I22
J 0
(-6800 3575);
DISPLAY 0.723404 (-6800 3575);
PAINT GREEN (-6800 3575);
DISPLAY INVISIBLE (-6800 3575);
FORCEPROP 1 LAST NEEDS_NO_SIZE TRUE
J 0
(-6800 3575);
DISPLAY 0.723404 (-6800 3575);
PAINT GREEN (-6800 3575);
DISPLAY INVISIBLE (-6800 3575);
FORCEPROP 2 LAST CDS_LIB pure_quanta
J 0
(-6800 3575);
DISPLAY INVISIBLE (-6800 3575);
FORCEADD TAP..1
(-3175 3025);
FORCEPROP 3 LASTPIN (-3225 3025) SIG_NAME M_J_CPU0_SB_DQS_DN<8>
J 0
(-3215 3035);
DISPLAY 0.659574 (-3215 3035);
PAINT MONO (-3215 3035);
DISPLAY INVISIBLE (-3215 3035);
FORCEPROP 1 LASTPIN (-3225 3025) BN 8
J 0
(-3237 3033);
DISPLAY 0.489362 (-3237 3033);
PAINT GREEN (-3237 3033);
FORCEPROP 2 LAST CDS_LIB mstr_standard
J 0
(-3175 3025);
DISPLAY 0.723404 (-3175 3025);
PAINT MONO (-3175 3025);
DISPLAY INVISIBLE (-3175 3025);
FORCEPROP 1 LAST BODY_TYPE PLUMBING
J 0
(-3175 3075);
DISPLAY 0.872340 (-3175 3075);
PAINT GREEN (-3175 3075);
DISPLAY INVISIBLE (-3175 3075);
FORCEPROP 1 LAST HDL_TAP TRUE
J 0
(-2850 2900);
DISPLAY 0.872340 (-2850 2900);
DISPLAY INVISIBLE (-2850 2900);
FORCEPROP 1 LAST PATH I220
J 0
(-3177 3025);
DISPLAY 0.872340 (-3177 3025);
PAINT GREEN (-3177 3025);
DISPLAY INVISIBLE (-3177 3025);
FORCEADD TAP..1
(-3175 2825);
FORCEPROP 3 LASTPIN (-3225 2825) SIG_NAME M_J_CPU0_SB_DQS_DN<6>
J 0
(-3215 2835);
DISPLAY 0.659574 (-3215 2835);
PAINT MONO (-3215 2835);
DISPLAY INVISIBLE (-3215 2835);
FORCEPROP 1 LASTPIN (-3225 2825) BN 6
J 0
(-3237 2833);
DISPLAY 0.489362 (-3237 2833);
PAINT GREEN (-3237 2833);
FORCEPROP 2 LAST CDS_LIB mstr_standard
J 0
(-3175 2825);
DISPLAY 0.723404 (-3175 2825);
PAINT MONO (-3175 2825);
DISPLAY INVISIBLE (-3175 2825);
FORCEPROP 1 LAST BODY_TYPE PLUMBING
J 0
(-3175 2875);
DISPLAY 0.872340 (-3175 2875);
PAINT GREEN (-3175 2875);
DISPLAY INVISIBLE (-3175 2875);
FORCEPROP 1 LAST HDL_TAP TRUE
J 0
(-2850 2700);
DISPLAY 0.872340 (-2850 2700);
DISPLAY INVISIBLE (-2850 2700);
FORCEPROP 1 LAST PATH I221
J 0
(-3177 2825);
DISPLAY 0.872340 (-3177 2825);
PAINT GREEN (-3177 2825);
DISPLAY INVISIBLE (-3177 2825);
FORCEADD TAP..1
(-3175 2625);
FORCEPROP 3 LASTPIN (-3225 2625) SIG_NAME M_J_CPU0_SB_DQS_DN<4>
J 0
(-3215 2635);
DISPLAY 0.659574 (-3215 2635);
PAINT MONO (-3215 2635);
DISPLAY INVISIBLE (-3215 2635);
FORCEPROP 1 LASTPIN (-3225 2625) BN 4
J 0
(-3237 2633);
DISPLAY 0.489362 (-3237 2633);
PAINT GREEN (-3237 2633);
FORCEPROP 2 LAST CDS_LIB mstr_standard
J 0
(-3175 2625);
DISPLAY 0.723404 (-3175 2625);
PAINT MONO (-3175 2625);
DISPLAY INVISIBLE (-3175 2625);
FORCEPROP 1 LAST BODY_TYPE PLUMBING
J 0
(-3175 2675);
DISPLAY 0.872340 (-3175 2675);
PAINT GREEN (-3175 2675);
DISPLAY INVISIBLE (-3175 2675);
FORCEPROP 1 LAST HDL_TAP TRUE
J 0
(-2850 2500);
DISPLAY 0.872340 (-2850 2500);
DISPLAY INVISIBLE (-2850 2500);
FORCEPROP 1 LAST PATH I222
J 0
(-3177 2625);
DISPLAY 0.872340 (-3177 2625);
PAINT GREEN (-3177 2625);
DISPLAY INVISIBLE (-3177 2625);
FORCEADD TAP..1
(-3175 2725);
FORCEPROP 3 LASTPIN (-3225 2725) SIG_NAME M_J_CPU0_SB_DQS_DN<5>
J 0
(-3215 2735);
DISPLAY 0.659574 (-3215 2735);
PAINT MONO (-3215 2735);
DISPLAY INVISIBLE (-3215 2735);
FORCEPROP 1 LASTPIN (-3225 2725) BN 5
J 0
(-3237 2733);
DISPLAY 0.489362 (-3237 2733);
PAINT GREEN (-3237 2733);
FORCEPROP 2 LAST CDS_LIB mstr_standard
J 0
(-3175 2725);
DISPLAY 0.723404 (-3175 2725);
PAINT MONO (-3175 2725);
DISPLAY INVISIBLE (-3175 2725);
FORCEPROP 1 LAST BODY_TYPE PLUMBING
J 0
(-3175 2775);
DISPLAY 0.872340 (-3175 2775);
PAINT GREEN (-3175 2775);
DISPLAY INVISIBLE (-3175 2775);
FORCEPROP 1 LAST HDL_TAP TRUE
J 0
(-2850 2600);
DISPLAY 0.872340 (-2850 2600);
DISPLAY INVISIBLE (-2850 2600);
FORCEPROP 1 LAST PATH I223
J 0
(-3177 2725);
DISPLAY 0.872340 (-3177 2725);
PAINT GREEN (-3177 2725);
DISPLAY INVISIBLE (-3177 2725);
FORCEADD TAP..1
(-3175 2525);
FORCEPROP 3 LASTPIN (-3225 2525) SIG_NAME M_J_CPU0_SB_DQS_DN<3>
J 0
(-3215 2535);
DISPLAY 0.659574 (-3215 2535);
PAINT MONO (-3215 2535);
DISPLAY INVISIBLE (-3215 2535);
FORCEPROP 1 LASTPIN (-3225 2525) BN 3
J 0
(-3237 2533);
DISPLAY 0.489362 (-3237 2533);
PAINT GREEN (-3237 2533);
FORCEPROP 2 LAST CDS_LIB mstr_standard
J 0
(-3175 2525);
DISPLAY 0.723404 (-3175 2525);
PAINT MONO (-3175 2525);
DISPLAY INVISIBLE (-3175 2525);
FORCEPROP 1 LAST BODY_TYPE PLUMBING
J 0
(-3175 2575);
DISPLAY 0.872340 (-3175 2575);
PAINT GREEN (-3175 2575);
DISPLAY INVISIBLE (-3175 2575);
FORCEPROP 1 LAST HDL_TAP TRUE
J 0
(-2850 2400);
DISPLAY 0.872340 (-2850 2400);
DISPLAY INVISIBLE (-2850 2400);
FORCEPROP 1 LAST PATH I224
J 0
(-3177 2525);
DISPLAY 0.872340 (-3177 2525);
PAINT GREEN (-3177 2525);
DISPLAY INVISIBLE (-3177 2525);
FORCEADD TAP..1
(-3175 2325);
FORCEPROP 3 LASTPIN (-3225 2325) SIG_NAME M_J_CPU0_SB_DQS_DN<1>
J 0
(-3215 2335);
DISPLAY 0.659574 (-3215 2335);
PAINT MONO (-3215 2335);
DISPLAY INVISIBLE (-3215 2335);
FORCEPROP 1 LASTPIN (-3225 2325) BN 1
J 0
(-3237 2333);
DISPLAY 0.489362 (-3237 2333);
PAINT GREEN (-3237 2333);
FORCEPROP 2 LAST CDS_LIB mstr_standard
J 0
(-3175 2325);
DISPLAY 0.723404 (-3175 2325);
PAINT MONO (-3175 2325);
DISPLAY INVISIBLE (-3175 2325);
FORCEPROP 1 LAST BODY_TYPE PLUMBING
J 0
(-3175 2375);
DISPLAY 0.872340 (-3175 2375);
PAINT GREEN (-3175 2375);
DISPLAY INVISIBLE (-3175 2375);
FORCEPROP 1 LAST HDL_TAP TRUE
J 0
(-2850 2200);
DISPLAY 0.872340 (-2850 2200);
DISPLAY INVISIBLE (-2850 2200);
FORCEPROP 1 LAST PATH I225
J 0
(-3177 2325);
DISPLAY 0.872340 (-3177 2325);
PAINT GREEN (-3177 2325);
DISPLAY INVISIBLE (-3177 2325);
FORCEADD TAP..1
(-3175 2425);
FORCEPROP 3 LASTPIN (-3225 2425) SIG_NAME M_J_CPU0_SB_DQS_DN<2>
J 0
(-3215 2435);
DISPLAY 0.659574 (-3215 2435);
PAINT MONO (-3215 2435);
DISPLAY INVISIBLE (-3215 2435);
FORCEPROP 1 LASTPIN (-3225 2425) BN 2
J 0
(-3237 2433);
DISPLAY 0.489362 (-3237 2433);
PAINT GREEN (-3237 2433);
FORCEPROP 2 LAST CDS_LIB mstr_standard
J 0
(-3175 2425);
DISPLAY 0.723404 (-3175 2425);
PAINT MONO (-3175 2425);
DISPLAY INVISIBLE (-3175 2425);
FORCEPROP 1 LAST BODY_TYPE PLUMBING
J 0
(-3175 2475);
DISPLAY 0.872340 (-3175 2475);
PAINT GREEN (-3175 2475);
DISPLAY INVISIBLE (-3175 2475);
FORCEPROP 1 LAST HDL_TAP TRUE
J 0
(-2850 2300);
DISPLAY 0.872340 (-2850 2300);
DISPLAY INVISIBLE (-2850 2300);
FORCEPROP 1 LAST PATH I226
J 0
(-3177 2425);
DISPLAY 0.872340 (-3177 2425);
PAINT GREEN (-3177 2425);
DISPLAY INVISIBLE (-3177 2425);
FORCEADD TAP..1
(-3175 2225);
FORCEPROP 3 LASTPIN (-3225 2225) SIG_NAME M_J_CPU0_SB_DQS_DN<0>
J 0
(-3215 2235);
DISPLAY 0.659574 (-3215 2235);
PAINT MONO (-3215 2235);
DISPLAY INVISIBLE (-3215 2235);
FORCEPROP 1 LASTPIN (-3225 2225) BN 0
J 0
(-3237 2233);
DISPLAY 0.489362 (-3237 2233);
PAINT GREEN (-3237 2233);
FORCEPROP 2 LAST CDS_LIB mstr_standard
J 0
(-3175 2225);
DISPLAY 0.723404 (-3175 2225);
PAINT MONO (-3175 2225);
DISPLAY INVISIBLE (-3175 2225);
FORCEPROP 1 LAST BODY_TYPE PLUMBING
J 0
(-3175 2275);
DISPLAY 0.872340 (-3175 2275);
PAINT GREEN (-3175 2275);
DISPLAY INVISIBLE (-3175 2275);
FORCEPROP 1 LAST HDL_TAP TRUE
J 0
(-2850 2100);
DISPLAY 0.872340 (-2850 2100);
DISPLAY INVISIBLE (-2850 2100);
FORCEPROP 1 LAST PATH I227
J 0
(-3177 2225);
DISPLAY 0.872340 (-3177 2225);
PAINT GREEN (-3177 2225);
DISPLAY INVISIBLE (-3177 2225);
FORCEADD TAP..1
(-3375 2975);
FORCEPROP 3 LASTPIN (-3425 2975) SIG_NAME M_J_CPU0_SB_DQS_DP<7>
J 0
(-3415 2985);
DISPLAY 0.659574 (-3415 2985);
PAINT MONO (-3415 2985);
DISPLAY INVISIBLE (-3415 2985);
FORCEPROP 1 LASTPIN (-3425 2975) BN 7
J 0
(-3437 2983);
DISPLAY 0.489362 (-3437 2983);
PAINT GREEN (-3437 2983);
FORCEPROP 2 LAST CDS_LIB mstr_standard
J 0
(-3375 2975);
DISPLAY 0.723404 (-3375 2975);
PAINT MONO (-3375 2975);
DISPLAY INVISIBLE (-3375 2975);
FORCEPROP 1 LAST BODY_TYPE PLUMBING
J 0
(-3375 3025);
DISPLAY 0.872340 (-3375 3025);
PAINT GREEN (-3375 3025);
DISPLAY INVISIBLE (-3375 3025);
FORCEPROP 1 LAST HDL_TAP TRUE
J 0
(-3050 2850);
DISPLAY 0.872340 (-3050 2850);
DISPLAY INVISIBLE (-3050 2850);
FORCEPROP 1 LAST PATH I228
J 0
(-3377 2975);
DISPLAY 0.872340 (-3377 2975);
PAINT GREEN (-3377 2975);
DISPLAY INVISIBLE (-3377 2975);
FORCEADD TAP..1
(-3375 2875);
FORCEPROP 3 LASTPIN (-3425 2875) SIG_NAME M_J_CPU0_SB_DQS_DP<6>
J 0
(-3415 2885);
DISPLAY 0.659574 (-3415 2885);
PAINT MONO (-3415 2885);
DISPLAY INVISIBLE (-3415 2885);
FORCEPROP 1 LASTPIN (-3425 2875) BN 6
J 0
(-3437 2883);
DISPLAY 0.489362 (-3437 2883);
PAINT GREEN (-3437 2883);
FORCEPROP 2 LAST CDS_LIB mstr_standard
J 0
(-3375 2875);
DISPLAY 0.723404 (-3375 2875);
PAINT MONO (-3375 2875);
DISPLAY INVISIBLE (-3375 2875);
FORCEPROP 1 LAST BODY_TYPE PLUMBING
J 0
(-3375 2925);
DISPLAY 0.872340 (-3375 2925);
PAINT GREEN (-3375 2925);
DISPLAY INVISIBLE (-3375 2925);
FORCEPROP 1 LAST HDL_TAP TRUE
J 0
(-3050 2750);
DISPLAY 0.872340 (-3050 2750);
DISPLAY INVISIBLE (-3050 2750);
FORCEPROP 1 LAST PATH I229
J 0
(-3377 2875);
DISPLAY 0.872340 (-3377 2875);
PAINT GREEN (-3377 2875);
DISPLAY INVISIBLE (-3377 2875);
FORCEADD TAP..1
R 2
(-7650 3125);
FORCEPROP 3 LASTPIN (-7600 3125) SIG_NAME M_J_CPU0_SB_CB<0>
J 0
(-7590 3135);
DISPLAY 0.659574 (-7590 3135);
PAINT MONO (-7590 3135);
DISPLAY INVISIBLE (-7590 3135);
FORCEPROP 1 LASTPIN (-7600 3125) BN 0
J 2
(-7588 3133);
DISPLAY 0.489362 (-7588 3133);
PAINT GREEN (-7588 3133);
FORCEPROP 2 LAST CDS_LIB mstr_standard
J 0
(-7650 3125);
DISPLAY 0.723404 (-7650 3125);
PAINT MONO (-7650 3125);
DISPLAY INVISIBLE (-7650 3125);
FORCEPROP 1 LAST BODY_TYPE PLUMBING
J 2
(-7650 3175);
DISPLAY 0.872340 (-7650 3175);
PAINT GREEN (-7650 3175);
DISPLAY INVISIBLE (-7650 3175);
FORCEPROP 1 LAST HDL_TAP TRUE
J 2
(-7975 3000);
DISPLAY 0.872340 (-7975 3000);
DISPLAY INVISIBLE (-7975 3000);
FORCEPROP 1 LAST PATH I23
J 2
(-7648 3125);
DISPLAY 0.872340 (-7648 3125);
PAINT GREEN (-7648 3125);
DISPLAY INVISIBLE (-7648 3125);
FORCEADD TAP..1
(-3375 2675);
FORCEPROP 3 LASTPIN (-3425 2675) SIG_NAME M_J_CPU0_SB_DQS_DP<4>
J 0
(-3415 2685);
DISPLAY 0.659574 (-3415 2685);
PAINT MONO (-3415 2685);
DISPLAY INVISIBLE (-3415 2685);
FORCEPROP 1 LASTPIN (-3425 2675) BN 4
J 0
(-3437 2683);
DISPLAY 0.489362 (-3437 2683);
PAINT GREEN (-3437 2683);
FORCEPROP 2 LAST CDS_LIB mstr_standard
J 0
(-3375 2675);
DISPLAY 0.723404 (-3375 2675);
PAINT MONO (-3375 2675);
DISPLAY INVISIBLE (-3375 2675);
FORCEPROP 1 LAST BODY_TYPE PLUMBING
J 0
(-3375 2725);
DISPLAY 0.872340 (-3375 2725);
PAINT GREEN (-3375 2725);
DISPLAY INVISIBLE (-3375 2725);
FORCEPROP 1 LAST HDL_TAP TRUE
J 0
(-3050 2550);
DISPLAY 0.872340 (-3050 2550);
DISPLAY INVISIBLE (-3050 2550);
FORCEPROP 1 LAST PATH I230
J 0
(-3377 2675);
DISPLAY 0.872340 (-3377 2675);
PAINT GREEN (-3377 2675);
DISPLAY INVISIBLE (-3377 2675);
FORCEADD TAP..1
(-3375 2775);
FORCEPROP 3 LASTPIN (-3425 2775) SIG_NAME M_J_CPU0_SB_DQS_DP<5>
J 0
(-3415 2785);
DISPLAY 0.659574 (-3415 2785);
PAINT MONO (-3415 2785);
DISPLAY INVISIBLE (-3415 2785);
FORCEPROP 1 LASTPIN (-3425 2775) BN 5
J 0
(-3437 2783);
DISPLAY 0.489362 (-3437 2783);
PAINT GREEN (-3437 2783);
FORCEPROP 2 LAST CDS_LIB mstr_standard
J 0
(-3375 2775);
DISPLAY 0.723404 (-3375 2775);
PAINT MONO (-3375 2775);
DISPLAY INVISIBLE (-3375 2775);
FORCEPROP 1 LAST BODY_TYPE PLUMBING
J 0
(-3375 2825);
DISPLAY 0.872340 (-3375 2825);
PAINT GREEN (-3375 2825);
DISPLAY INVISIBLE (-3375 2825);
FORCEPROP 1 LAST HDL_TAP TRUE
J 0
(-3050 2650);
DISPLAY 0.872340 (-3050 2650);
DISPLAY INVISIBLE (-3050 2650);
FORCEPROP 1 LAST PATH I231
J 0
(-3377 2775);
DISPLAY 0.872340 (-3377 2775);
PAINT GREEN (-3377 2775);
DISPLAY INVISIBLE (-3377 2775);
FORCEADD TAP..1
(-3375 2575);
FORCEPROP 3 LASTPIN (-3425 2575) SIG_NAME M_J_CPU0_SB_DQS_DP<3>
J 0
(-3415 2585);
DISPLAY 0.659574 (-3415 2585);
PAINT MONO (-3415 2585);
DISPLAY INVISIBLE (-3415 2585);
FORCEPROP 1 LASTPIN (-3425 2575) BN 3
J 0
(-3437 2583);
DISPLAY 0.489362 (-3437 2583);
PAINT GREEN (-3437 2583);
FORCEPROP 2 LAST CDS_LIB mstr_standard
J 0
(-3375 2575);
DISPLAY 0.723404 (-3375 2575);
PAINT MONO (-3375 2575);
DISPLAY INVISIBLE (-3375 2575);
FORCEPROP 1 LAST BODY_TYPE PLUMBING
J 0
(-3375 2625);
DISPLAY 0.872340 (-3375 2625);
PAINT GREEN (-3375 2625);
DISPLAY INVISIBLE (-3375 2625);
FORCEPROP 1 LAST HDL_TAP TRUE
J 0
(-3050 2450);
DISPLAY 0.872340 (-3050 2450);
DISPLAY INVISIBLE (-3050 2450);
FORCEPROP 1 LAST PATH I232
J 0
(-3377 2575);
DISPLAY 0.872340 (-3377 2575);
PAINT GREEN (-3377 2575);
DISPLAY INVISIBLE (-3377 2575);
FORCEADD TAP..1
(-3375 2475);
FORCEPROP 3 LASTPIN (-3425 2475) SIG_NAME M_J_CPU0_SB_DQS_DP<2>
J 0
(-3415 2485);
DISPLAY 0.659574 (-3415 2485);
PAINT MONO (-3415 2485);
DISPLAY INVISIBLE (-3415 2485);
FORCEPROP 1 LASTPIN (-3425 2475) BN 2
J 0
(-3437 2483);
DISPLAY 0.489362 (-3437 2483);
PAINT GREEN (-3437 2483);
FORCEPROP 2 LAST CDS_LIB mstr_standard
J 0
(-3375 2475);
DISPLAY 0.723404 (-3375 2475);
PAINT MONO (-3375 2475);
DISPLAY INVISIBLE (-3375 2475);
FORCEPROP 1 LAST BODY_TYPE PLUMBING
J 0
(-3375 2525);
DISPLAY 0.872340 (-3375 2525);
PAINT GREEN (-3375 2525);
DISPLAY INVISIBLE (-3375 2525);
FORCEPROP 1 LAST HDL_TAP TRUE
J 0
(-3050 2350);
DISPLAY 0.872340 (-3050 2350);
DISPLAY INVISIBLE (-3050 2350);
FORCEPROP 1 LAST PATH I233
J 0
(-3377 2475);
DISPLAY 0.872340 (-3377 2475);
PAINT GREEN (-3377 2475);
DISPLAY INVISIBLE (-3377 2475);
FORCEADD TAP..1
(-3375 2375);
FORCEPROP 3 LASTPIN (-3425 2375) SIG_NAME M_J_CPU0_SB_DQS_DP<1>
J 0
(-3415 2385);
DISPLAY 0.659574 (-3415 2385);
PAINT MONO (-3415 2385);
DISPLAY INVISIBLE (-3415 2385);
FORCEPROP 1 LASTPIN (-3425 2375) BN 1
J 0
(-3437 2383);
DISPLAY 0.489362 (-3437 2383);
PAINT GREEN (-3437 2383);
FORCEPROP 2 LAST CDS_LIB mstr_standard
J 0
(-3375 2375);
DISPLAY 0.723404 (-3375 2375);
PAINT MONO (-3375 2375);
DISPLAY INVISIBLE (-3375 2375);
FORCEPROP 1 LAST BODY_TYPE PLUMBING
J 0
(-3375 2425);
DISPLAY 0.872340 (-3375 2425);
PAINT GREEN (-3375 2425);
DISPLAY INVISIBLE (-3375 2425);
FORCEPROP 1 LAST HDL_TAP TRUE
J 0
(-3050 2250);
DISPLAY 0.872340 (-3050 2250);
DISPLAY INVISIBLE (-3050 2250);
FORCEPROP 1 LAST PATH I234
J 0
(-3377 2375);
DISPLAY 0.872340 (-3377 2375);
PAINT GREEN (-3377 2375);
DISPLAY INVISIBLE (-3377 2375);
FORCEADD TAP..1
(-3375 2275);
FORCEPROP 3 LASTPIN (-3425 2275) SIG_NAME M_J_CPU0_SB_DQS_DP<0>
J 0
(-3415 2285);
DISPLAY 0.659574 (-3415 2285);
PAINT MONO (-3415 2285);
DISPLAY INVISIBLE (-3415 2285);
FORCEPROP 1 LASTPIN (-3425 2275) BN 0
J 0
(-3437 2283);
DISPLAY 0.489362 (-3437 2283);
PAINT GREEN (-3437 2283);
FORCEPROP 2 LAST CDS_LIB mstr_standard
J 0
(-3375 2275);
DISPLAY 0.723404 (-3375 2275);
PAINT MONO (-3375 2275);
DISPLAY INVISIBLE (-3375 2275);
FORCEPROP 1 LAST BODY_TYPE PLUMBING
J 0
(-3375 2325);
DISPLAY 0.872340 (-3375 2325);
PAINT GREEN (-3375 2325);
DISPLAY INVISIBLE (-3375 2325);
FORCEPROP 1 LAST HDL_TAP TRUE
J 0
(-3050 2150);
DISPLAY 0.872340 (-3050 2150);
DISPLAY INVISIBLE (-3050 2150);
FORCEPROP 1 LAST PATH I235
J 0
(-3377 2275);
DISPLAY 0.872340 (-3377 2275);
PAINT GREEN (-3377 2275);
DISPLAY INVISIBLE (-3377 2275);
FORCEADD SCONN288_DDR506112002KQ..2
(-4325 3225);
FORCEPROP 1 LAST LOCATION J68
J 0
(-4925 4550);
DISPLAY 0.468085 (-4925 4550);
PAINT SKYBLUE (-4925 4550);
FORCEPROP 0 LAST $SEC 2
J 0
(-4775 4700);
DISPLAY 0.680851 (-4775 4700);
PAINT MONO (-4775 4700);
DISPLAY INVISIBLE (-4775 4700);
FORCEPROP 0 LAST CDS_SEC 2
J 0
(-4775 4700);
DISPLAY 1.021277 (-4775 4700);
DISPLAY INVISIBLE (-4775 4700);
FORCEPROP 0 LASTPIN (-3575 3275) $PN 12
J 0
(-3565 3285);
DISPLAY 0.680851 (-3565 3285);
PAINT MONO (-3565 3285);
FORCEPROP 0 LASTPIN (-3575 3325) $PN 11
J 0
(-3565 3335);
DISPLAY 0.680851 (-3565 3335);
PAINT MONO (-3565 3335);
FORCEPROP 0 LASTPIN (-3575 2225) $PN 105
J 0
(-3565 2235);
DISPLAY 0.680851 (-3565 2235);
PAINT MONO (-3565 2235);
FORCEPROP 0 LASTPIN (-3575 2275) $PN 104
J 0
(-3565 2285);
DISPLAY 0.680851 (-3565 2285);
PAINT MONO (-3565 2285);
FORCEPROP 0 LASTPIN (-3575 3375) $PN 23
J 0
(-3565 3385);
DISPLAY 0.680851 (-3565 3385);
PAINT MONO (-3565 3385);
FORCEPROP 0 LASTPIN (-3575 3425) $PN 22
J 0
(-3565 3435);
DISPLAY 0.680851 (-3565 3435);
PAINT MONO (-3565 3435);
FORCEPROP 0 LASTPIN (-3575 2325) $PN 116
J 0
(-3565 2335);
DISPLAY 0.680851 (-3565 2335);
PAINT MONO (-3565 2335);
FORCEPROP 0 LASTPIN (-3575 2375) $PN 115
J 0
(-3565 2385);
DISPLAY 0.680851 (-3565 2385);
PAINT MONO (-3565 2385);
FORCEPROP 0 LASTPIN (-3575 3475) $PN 34
J 0
(-3565 3485);
DISPLAY 0.680851 (-3565 3485);
PAINT MONO (-3565 3485);
FORCEPROP 0 LASTPIN (-3575 3525) $PN 33
J 0
(-3565 3535);
DISPLAY 0.680851 (-3565 3535);
PAINT MONO (-3565 3535);
FORCEPROP 0 LASTPIN (-3575 2425) $PN 127
J 0
(-3565 2435);
DISPLAY 0.680851 (-3565 2435);
PAINT MONO (-3565 2435);
FORCEPROP 0 LASTPIN (-3575 2475) $PN 126
J 0
(-3565 2485);
DISPLAY 0.680851 (-3565 2485);
PAINT MONO (-3565 2485);
FORCEPROP 0 LASTPIN (-3575 3575) $PN 45
J 0
(-3565 3585);
DISPLAY 0.680851 (-3565 3585);
PAINT MONO (-3565 3585);
FORCEPROP 0 LASTPIN (-3575 3625) $PN 44
J 0
(-3565 3635);
DISPLAY 0.680851 (-3565 3635);
PAINT MONO (-3565 3635);
FORCEPROP 0 LASTPIN (-3575 2525) $PN 138
J 0
(-3565 2535);
DISPLAY 0.680851 (-3565 2535);
PAINT MONO (-3565 2535);
FORCEPROP 0 LASTPIN (-3575 2575) $PN 137
J 0
(-3565 2585);
DISPLAY 0.680851 (-3565 2585);
PAINT MONO (-3565 2585);
FORCEPROP 0 LASTPIN (-3575 3675) $PN 56
J 0
(-3565 3685);
DISPLAY 0.680851 (-3565 3685);
PAINT MONO (-3565 3685);
FORCEPROP 0 LASTPIN (-3575 3725) $PN 55
J 0
(-3565 3735);
DISPLAY 0.680851 (-3565 3735);
PAINT MONO (-3565 3735);
FORCEPROP 0 LASTPIN (-3575 2625) $PN 238
J 0
(-3565 2635);
DISPLAY 0.680851 (-3565 2635);
PAINT MONO (-3565 2635);
FORCEPROP 0 LASTPIN (-3575 2675) $PN 239
J 0
(-3565 2685);
DISPLAY 0.680851 (-3565 2685);
PAINT MONO (-3565 2685);
FORCEPROP 0 LASTPIN (-3575 3775) $PN 156
J 0
(-3565 3785);
DISPLAY 0.680851 (-3565 3785);
PAINT MONO (-3565 3785);
FORCEPROP 0 LASTPIN (-3575 3825) $PN 157
J 0
(-3565 3835);
DISPLAY 0.680851 (-3565 3835);
PAINT MONO (-3565 3835);
FORCEPROP 0 LASTPIN (-3575 2725) $PN 249
J 0
(-3565 2735);
DISPLAY 0.680851 (-3565 2735);
PAINT MONO (-3565 2735);
FORCEPROP 0 LASTPIN (-3575 2775) $PN 250
J 0
(-3565 2785);
DISPLAY 0.680851 (-3565 2785);
PAINT MONO (-3565 2785);
FORCEPROP 0 LASTPIN (-3575 3875) $PN 167
J 0
(-3565 3885);
DISPLAY 0.680851 (-3565 3885);
PAINT MONO (-3565 3885);
FORCEPROP 0 LASTPIN (-3575 3925) $PN 168
J 0
(-3565 3935);
DISPLAY 0.680851 (-3565 3935);
PAINT MONO (-3565 3935);
FORCEPROP 0 LASTPIN (-3575 2825) $PN 260
J 0
(-3565 2835);
DISPLAY 0.680851 (-3565 2835);
PAINT MONO (-3565 2835);
FORCEPROP 0 LASTPIN (-3575 2875) $PN 261
J 0
(-3565 2885);
DISPLAY 0.680851 (-3565 2885);
PAINT MONO (-3565 2885);
FORCEPROP 0 LASTPIN (-3575 3975) $PN 178
J 0
(-3565 3985);
DISPLAY 0.680851 (-3565 3985);
PAINT MONO (-3565 3985);
FORCEPROP 0 LASTPIN (-3575 4025) $PN 179
J 0
(-3565 4035);
DISPLAY 0.680851 (-3565 4035);
PAINT MONO (-3565 4035);
FORCEPROP 0 LASTPIN (-3575 2925) $PN 271
J 0
(-3565 2935);
DISPLAY 0.680851 (-3565 2935);
PAINT MONO (-3565 2935);
FORCEPROP 0 LASTPIN (-3575 2975) $PN 272
J 0
(-3565 2985);
DISPLAY 0.680851 (-3565 2985);
PAINT MONO (-3565 2985);
FORCEPROP 0 LASTPIN (-3575 4075) $PN 189
J 0
(-3565 4085);
DISPLAY 0.680851 (-3565 4085);
PAINT MONO (-3565 4085);
FORCEPROP 0 LASTPIN (-3575 4125) $PN 190
J 0
(-3565 4135);
DISPLAY 0.680851 (-3565 4135);
PAINT MONO (-3565 4135);
FORCEPROP 0 LASTPIN (-3575 3025) $PN 282
J 0
(-3565 3035);
DISPLAY 0.680851 (-3565 3035);
PAINT MONO (-3565 3035);
FORCEPROP 0 LASTPIN (-3575 3075) $PN 283
J 0
(-3565 3085);
DISPLAY 0.680851 (-3565 3085);
PAINT MONO (-3565 3085);
FORCEPROP 0 LASTPIN (-3575 4175) $PN 200
J 0
(-3565 4185);
DISPLAY 0.680851 (-3565 4185);
PAINT MONO (-3565 4185);
FORCEPROP 0 LASTPIN (-3575 4225) $PN 201
J 0
(-3565 4235);
DISPLAY 0.680851 (-3565 4235);
PAINT MONO (-3565 4235);
FORCEPROP 0 LASTPIN (-3575 3125) $PN 94
J 0
(-3565 3135);
DISPLAY 0.680851 (-3565 3135);
PAINT MONO (-3565 3135);
FORCEPROP 0 LASTPIN (-3575 3175) $PN 93
J 0
(-3565 3185);
DISPLAY 0.680851 (-3565 3185);
PAINT MONO (-3565 3185);
FORCEPROP 1 LAST MATERIAL IO
J 0
(-4925 4400);
DISPLAY 0.468085 (-4925 4400);
PAINT SKYBLUE (-4925 4400);
FORCEPROP 1 LAST PART_NUMBER DFHST8FS479
J 0
(-4925 4475);
DISPLAY 0.468085 (-4925 4475);
PAINT SKYBLUE (-4925 4475);
FORCEPROP 2 LAST VALUE SCONN288_DDR506112002KQ
J 0
(-4775 4600);
DISPLAY 0.489362 (-4775 4600);
PAINT SKYBLUE (-4775 4600);
FORCEPROP 2 LAST PART_TYPE SMLF
J 0
(-4775 4650);
DISPLAY 1.021277 (-4775 4650);
FORCEPROP 1 LAST CDS_LMAN_SYM_OUTLINE -600,1150,600,-1150
J 0
(-4325 3225);
DISPLAY 0.468085 (-4325 3225);
PAINT GREEN (-4325 3225);
DISPLAY INVISIBLE (-4325 3225);
FORCEPROP 1 LAST PATH I236
J 0
(-4325 3225);
DISPLAY 0.723404 (-4325 3225);
PAINT GREEN (-4325 3225);
DISPLAY INVISIBLE (-4325 3225);
FORCEPROP 1 LAST NEEDS_NO_SIZE TRUE
J 0
(-4325 3225);
DISPLAY 0.723404 (-4325 3225);
PAINT GREEN (-4325 3225);
DISPLAY INVISIBLE (-4325 3225);
FORCEPROP 2 LAST CDS_LIB pure_quanta
J 0
(-4325 3225);
DISPLAY INVISIBLE (-4325 3225);
FORCEADD GND..1
(-2750 5475);
FORCEPROP 3 LASTPIN (-2750 5525) SIG_NAME GND\g
J 0
(-2740 5535);
DISPLAY 0.659574 (-2740 5535);
PAINT MONO (-2740 5535);
DISPLAY INVISIBLE (-2740 5535);
FORCEPROP 2 LAST CDS_LIB pure_quanta_power
J 0
(-2750 5475);
DISPLAY INVISIBLE (-2750 5475);
FORCEPROP 2 LAST BOM_COST MEM
J 0
(-2725 5600);
DISPLAY 0.659574 (-2725 5600);
DISPLAY INVISIBLE (-2725 5600);
FORCEPROP 1 LAST SIZE 1B
J 0
(-2675 5425);
DISPLAY 0.723404 (-2675 5425);
PAINT GREEN (-2675 5425);
DISPLAY INVISIBLE (-2675 5425);
FORCEPROP 1 LAST PATH I237
J 0
(-2675 5475);
DISPLAY 0.872340 (-2675 5475);
PAINT AQUA (-2675 5475);
DISPLAY INVISIBLE (-2675 5475);
FORCEPROP 2 LAST ROOM MEM_EFGH_DECOUPLING_CAPS
J 0
(-2725 5550);
DISPLAY 0.659574 (-2725 5550);
PAINT RED (-2725 5550);
DISPLAY INVISIBLE (-2725 5550);
FORCEPROP 1 LAST HDL_POWER GND
J 0
(-2750 5625);
DISPLAY 0.723404 (-2750 5625);
PAINT GREEN (-2750 5625);
DISPLAY INVISIBLE (-2750 5625);
FORCEADD Q_CAP..1
R 2
(-2750 5825);
FORCEPROP 1 LAST LOCATION C165
J 2
(-2800 5925);
DISPLAY 0.489362 (-2800 5925);
PAINT SKYBLUE (-2800 5925);
FORCEPROP 0 LAST $SEC 1
J 0
(-2800 5975);
DISPLAY 0.680851 (-2800 5975);
PAINT MONO (-2800 5975);
DISPLAY INVISIBLE (-2800 5975);
FORCEPROP 0 LAST CDS_SEC 1
J 0
(-2800 5975);
DISPLAY 0.680851 (-2800 5975);
DISPLAY INVISIBLE (-2800 5975);
FORCEPROP 1 LASTPIN (-2750 5925) $PN 1
J 2
(-2760 5905);
DISPLAY 0.489362 (-2760 5905);
PAINT MONO (-2760 5905);
FORCEPROP 1 LASTPIN (-2750 5725) $PN 2
J 2
(-2760 5705);
DISPLAY 0.489362 (-2760 5705);
PAINT MONO (-2760 5705);
FORCEPROP 1 LAST MATERIAL X6S
J 2
(-2800 5725);
DISPLAY 0.489362 (-2800 5725);
PAINT SKYBLUE (-2800 5725);
FORCEPROP 1 LAST TOLERANCE 10%
J 2
(-2800 5775);
DISPLAY 0.489362 (-2800 5775);
PAINT SKYBLUE (-2800 5775);
FORCEPROP 1 LAST VALUE 10UF
J 2
(-2800 5875);
DISPLAY 0.489362 (-2800 5875);
PAINT SKYBLUE (-2800 5875);
FORCEPROP 1 LAST PACK_TYPE C0805
J 2
(-2800 5625);
DISPLAY 0.489362 (-2800 5625);
PAINT SKYBLUE (-2800 5625);
FORCEPROP 1 LAST VOLTAGE 25V
J 2
(-2800 5825);
DISPLAY 0.489362 (-2800 5825);
PAINT SKYBLUE (-2800 5825);
FORCEPROP 1 LAST PART_NUMBER CH6104KEA00
J 2
(-2800 5675);
DISPLAY 0.489362 (-2800 5675);
PAINT SKYBLUE (-2800 5675);
FORCEPROP 0 LAST BOM_COST MEM
J 2
(-2805 5970);
DISPLAY 0.595745 (-2805 5970);
PAINT MONO (-2805 5970);
DISPLAY INVISIBLE (-2805 5970);
FORCEPROP 2 LAST CDS_LIB pure_quanta
J 0
(-2750 5825);
DISPLAY INVISIBLE (-2750 5825);
FORCEPROP 1 LAST PATH I238
J 2
(-2800 5975);
DISPLAY 0.978723 (-2800 5975);
PAINT WHITE (-2800 5975);
DISPLAY INVISIBLE (-2800 5975);
FORCEPROP 0 LAST ROOM MEM_CH_A_CPU0_DIMM1
J 2
(-2805 5970);
DISPLAY 0.595745 (-2805 5970);
PAINT RED (-2805 5970);
DISPLAY INVISIBLE (-2805 5970);
FORCEADD Q_CAP..1
R 2
(-2175 5825);
FORCEPROP 1 LAST LOCATION C166
J 2
(-2225 5925);
DISPLAY 0.489362 (-2225 5925);
PAINT SKYBLUE (-2225 5925);
FORCEPROP 0 LAST $SEC 1
J 0
(-2225 5975);
DISPLAY 0.680851 (-2225 5975);
PAINT MONO (-2225 5975);
DISPLAY INVISIBLE (-2225 5975);
FORCEPROP 0 LAST CDS_SEC 1
J 0
(-2225 5975);
DISPLAY 0.680851 (-2225 5975);
DISPLAY INVISIBLE (-2225 5975);
FORCEPROP 1 LASTPIN (-2175 5925) $PN 1
J 2
(-2185 5905);
DISPLAY 0.489362 (-2185 5905);
PAINT MONO (-2185 5905);
FORCEPROP 1 LASTPIN (-2175 5725) $PN 2
J 2
(-2185 5705);
DISPLAY 0.489362 (-2185 5705);
PAINT MONO (-2185 5705);
FORCEPROP 1 LAST MATERIAL X6S
J 2
(-2225 5725);
DISPLAY 0.489362 (-2225 5725);
PAINT SKYBLUE (-2225 5725);
FORCEPROP 1 LAST TOLERANCE 10%
J 2
(-2225 5775);
DISPLAY 0.489362 (-2225 5775);
PAINT SKYBLUE (-2225 5775);
FORCEPROP 1 LAST VALUE 10UF
J 2
(-2225 5875);
DISPLAY 0.489362 (-2225 5875);
PAINT SKYBLUE (-2225 5875);
FORCEPROP 1 LAST VOLTAGE 25V
J 2
(-2225 5825);
DISPLAY 0.489362 (-2225 5825);
PAINT SKYBLUE (-2225 5825);
FORCEPROP 1 LAST PACK_TYPE C0805
J 2
(-2225 5625);
DISPLAY 0.489362 (-2225 5625);
PAINT SKYBLUE (-2225 5625);
FORCEPROP 1 LAST PART_NUMBER CH6104KEA00
J 2
(-2225 5675);
DISPLAY 0.489362 (-2225 5675);
PAINT SKYBLUE (-2225 5675);
FORCEPROP 0 LAST BOM_COST MEM
J 2
(-2230 5970);
DISPLAY 0.595745 (-2230 5970);
PAINT MONO (-2230 5970);
DISPLAY INVISIBLE (-2230 5970);
FORCEPROP 2 LAST CDS_LIB pure_quanta
J 0
(-2175 5825);
DISPLAY INVISIBLE (-2175 5825);
FORCEPROP 1 LAST PATH I239
J 2
(-2225 5975);
DISPLAY 0.978723 (-2225 5975);
PAINT WHITE (-2225 5975);
DISPLAY INVISIBLE (-2225 5975);
FORCEPROP 0 LAST ROOM MEM_CH_A_CPU0_DIMM1
J 2
(-2230 5970);
DISPLAY 0.595745 (-2230 5970);
PAINT RED (-2230 5970);
DISPLAY INVISIBLE (-2230 5970);
FORCEADD TAP..1
R 2
(-7650 3175);
FORCEPROP 3 LASTPIN (-7600 3175) SIG_NAME M_J_CPU0_SB_CB<1>
J 0
(-7590 3185);
DISPLAY 0.659574 (-7590 3185);
PAINT MONO (-7590 3185);
DISPLAY INVISIBLE (-7590 3185);
FORCEPROP 1 LASTPIN (-7600 3175) BN 1
J 2
(-7588 3183);
DISPLAY 0.489362 (-7588 3183);
PAINT GREEN (-7588 3183);
FORCEPROP 2 LAST CDS_LIB mstr_standard
J 0
(-7650 3175);
DISPLAY 0.723404 (-7650 3175);
PAINT MONO (-7650 3175);
DISPLAY INVISIBLE (-7650 3175);
FORCEPROP 1 LAST BODY_TYPE PLUMBING
J 2
(-7650 3225);
DISPLAY 0.872340 (-7650 3225);
PAINT GREEN (-7650 3225);
DISPLAY INVISIBLE (-7650 3225);
FORCEPROP 1 LAST HDL_TAP TRUE
J 2
(-7975 3050);
DISPLAY 0.872340 (-7975 3050);
DISPLAY INVISIBLE (-7975 3050);
FORCEPROP 1 LAST PATH I24
J 2
(-7648 3175);
DISPLAY 0.872340 (-7648 3175);
PAINT GREEN (-7648 3175);
DISPLAY INVISIBLE (-7648 3175);
FORCEADD UNIVERSAL_POWER..1
(-2750 6150);
FORCEPROP 3 LASTPIN (-2750 6100) SIG_NAME P12V_MEM_0\g
J 0
(-2740 6110);
DISPLAY 0.659574 (-2740 6110);
PAINT MONO (-2740 6110);
DISPLAY INVISIBLE (-2740 6110);
FORCEPROP 1 LAST HDL_POWER P12V_MEM_0
J 1
(-2775 6200);
DISPLAY 0.489362 (-2775 6200);
PAINT GREEN (-2775 6200);
FORCEPROP 2 LAST BOM_COST VR_SYSTEM
J 0
(-2750 6250);
DISPLAY 0.617021 (-2750 6250);
PAINT PURPLE (-2750 6250);
DISPLAY INVISIBLE (-2750 6250);
FORCEPROP 2 LAST CDS_LIB pure_quanta_power
J 0
(-2750 6150);
DISPLAY INVISIBLE (-2750 6150);
FORCEPROP 1 LAST PATH I240
J 0
(-2700 6175);
DISPLAY 0.872340 (-2700 6175);
PAINT AQUA (-2700 6175);
DISPLAY INVISIBLE (-2700 6175);
FORCEADD OFFPAGE..1
(-8250 2625);
FORCEPROP 2 LAST $XR5 96 
J 0
(-8982 2625);
DISPLAY 0.638298 (-8982 2625);
PAINT MONO (-8982 2625);
FORCEPROP 2 LAST $XR4 95 
J 0
(-8892 2625);
DISPLAY 0.638298 (-8892 2625);
PAINT MONO (-8892 2625);
FORCEPROP 2 LAST $XR3 93 
J 0
(-8802 2625);
DISPLAY 0.638298 (-8802 2625);
PAINT MONO (-8802 2625);
FORCEPROP 2 LAST $XR2 92 
J 0
(-8712 2625);
DISPLAY 0.638298 (-8712 2625);
PAINT MONO (-8712 2625);
FORCEPROP 2 LAST $XR1 91 
J 0
(-8622 2625);
DISPLAY 0.638298 (-8622 2625);
PAINT MONO (-8622 2625);
FORCEPROP 2 LAST $XR0 136 
J 0
(-8532 2625);
DISPLAY 0.638298 (-8532 2625);
PAINT MONO (-8532 2625);
FORCEPROP 2 LAST PATH I241
J 0
(-8525 2675);
DISPLAY 0.680851 (-8525 2675);
DISPLAY INVISIBLE (-8525 2675);
FORCEPROP 1 LAST COMMENT_BODY TRUE
J 0
(-8125 2525);
DISPLAY 0.872340 (-8125 2525);
PAINT GREEN (-8125 2525);
DISPLAY INVISIBLE (-8125 2525);
FORCEPROP 1 LAST OFFPAGE TRUE
J 0
(-7925 2500);
DISPLAY 0.872340 (-7925 2500);
PAINT GREEN (-7925 2500);
DISPLAY INVISIBLE (-7925 2500);
FORCEPROP 2 LAST CDS_LIB mstr_standard
J 0
(-8250 2625);
DISPLAY 0.808511 (-8250 2625);
DISPLAY INVISIBLE (-8250 2625);
FORCEADD Q_RES..1
(-7700 2625);
FORCEPROP 1 LAST $LOCATION R1577
J 0
(-7750 2650);
DISPLAY 0.510638 (-7750 2650);
PAINT SKYBLUE (-7750 2650);
FORCEPROP 0 LAST CDS_LOCATION R1577
J 0
(-7750 2725);
DISPLAY 0.680851 (-7750 2725);
DISPLAY INVISIBLE (-7750 2725);
FORCEPROP 0 LAST $SEC 1
J 0
(-7750 2725);
DISPLAY 0.680851 (-7750 2725);
PAINT MONO (-7750 2725);
DISPLAY INVISIBLE (-7750 2725);
FORCEPROP 0 LAST CDS_SEC 1
J 0
(-7750 2725);
DISPLAY 0.680851 (-7750 2725);
DISPLAY INVISIBLE (-7750 2725);
FORCEPROP 1 LASTPIN (-7800 2625) $PN 1
J 0
(-7788 2637);
DISPLAY 0.787234 (-7788 2637);
PAINT MONO (-7788 2637);
FORCEPROP 1 LASTPIN (-7600 2625) $PN 2
J 0
(-7638 2637);
DISPLAY 0.787234 (-7638 2637);
PAINT MONO (-7638 2637);
FORCEPROP 1 LAST VALUE 49.9
J 2
(-7550 2675);
DISPLAY 0.510638 (-7550 2675);
PAINT SKYBLUE (-7550 2675);
FORCEPROP 2 LAST CDS_LIB pure_quanta
J 0
(-7700 2625);
DISPLAY INVISIBLE (-7700 2625);
FORCEPROP 1 LAST PATH I242
J 0
(-7750 2775);
DISPLAY 0.978723 (-7750 2775);
PAINT WHITE (-7750 2775);
DISPLAY INVISIBLE (-7750 2775);
FORCEPROP 1 LAST MATERIAL CHIP
J 0
(-7700 2475);
DISPLAY 0.978723 (-7700 2475);
DISPLAY INVISIBLE (-7700 2475);
FORCEPROP 1 LAST PACK_TYPE 0402LF
J 0
(-7450 2475);
DISPLAY 0.978723 (-7450 2475);
DISPLAY INVISIBLE (-7450 2475);
FORCEPROP 1 LAST WATTAGE 1/16W
J 2
(-7725 2475);
DISPLAY 0.978723 (-7725 2475);
DISPLAY INVISIBLE (-7725 2475);
FORCEPROP 1 LAST TOLERANCE 1%
J 0
(-7700 2525);
DISPLAY 0.978723 (-7700 2525);
DISPLAY INVISIBLE (-7700 2525);
FORCEPROP 1 LAST PART_NUMBER CS04992FB07
J 0
(-7750 2725);
DISPLAY 0.978723 (-7750 2725);
DISPLAY INVISIBLE (-7750 2725);
FORCEADD TAP..1
R 2
(-7650 3225);
FORCEPROP 3 LASTPIN (-7600 3225) SIG_NAME M_J_CPU0_SB_CB<2>
J 0
(-7590 3235);
DISPLAY 0.659574 (-7590 3235);
PAINT MONO (-7590 3235);
DISPLAY INVISIBLE (-7590 3235);
FORCEPROP 1 LASTPIN (-7600 3225) BN 2
J 2
(-7588 3233);
DISPLAY 0.489362 (-7588 3233);
PAINT GREEN (-7588 3233);
FORCEPROP 2 LAST CDS_LIB mstr_standard
J 0
(-7650 3225);
DISPLAY 0.723404 (-7650 3225);
PAINT MONO (-7650 3225);
DISPLAY INVISIBLE (-7650 3225);
FORCEPROP 1 LAST BODY_TYPE PLUMBING
J 2
(-7650 3275);
DISPLAY 0.872340 (-7650 3275);
PAINT GREEN (-7650 3275);
DISPLAY INVISIBLE (-7650 3275);
FORCEPROP 1 LAST HDL_TAP TRUE
J 2
(-7975 3100);
DISPLAY 0.872340 (-7975 3100);
DISPLAY INVISIBLE (-7975 3100);
FORCEPROP 1 LAST PATH I25
J 2
(-7648 3225);
DISPLAY 0.872340 (-7648 3225);
PAINT GREEN (-7648 3225);
DISPLAY INVISIBLE (-7648 3225);
FORCEADD TAP..1
R 2
(-7650 3275);
FORCEPROP 3 LASTPIN (-7600 3275) SIG_NAME M_J_CPU0_SB_CB<3>
J 0
(-7590 3285);
DISPLAY 0.659574 (-7590 3285);
PAINT MONO (-7590 3285);
DISPLAY INVISIBLE (-7590 3285);
FORCEPROP 1 LASTPIN (-7600 3275) BN 3
J 2
(-7588 3283);
DISPLAY 0.489362 (-7588 3283);
PAINT GREEN (-7588 3283);
FORCEPROP 2 LAST CDS_LIB mstr_standard
J 0
(-7650 3275);
DISPLAY 0.723404 (-7650 3275);
PAINT MONO (-7650 3275);
DISPLAY INVISIBLE (-7650 3275);
FORCEPROP 1 LAST BODY_TYPE PLUMBING
J 2
(-7650 3325);
DISPLAY 0.872340 (-7650 3325);
PAINT GREEN (-7650 3325);
DISPLAY INVISIBLE (-7650 3325);
FORCEPROP 1 LAST HDL_TAP TRUE
J 2
(-7975 3150);
DISPLAY 0.872340 (-7975 3150);
DISPLAY INVISIBLE (-7975 3150);
FORCEPROP 1 LAST PATH I26
J 2
(-7648 3275);
DISPLAY 0.872340 (-7648 3275);
PAINT GREEN (-7648 3275);
DISPLAY INVISIBLE (-7648 3275);
FORCEADD TAP..1
R 2
(-7650 3325);
FORCEPROP 3 LASTPIN (-7600 3325) SIG_NAME M_J_CPU0_SB_CB<4>
J 0
(-7590 3335);
DISPLAY 0.659574 (-7590 3335);
PAINT MONO (-7590 3335);
DISPLAY INVISIBLE (-7590 3335);
FORCEPROP 1 LASTPIN (-7600 3325) BN 4
J 2
(-7588 3333);
DISPLAY 0.489362 (-7588 3333);
PAINT GREEN (-7588 3333);
FORCEPROP 2 LAST CDS_LIB mstr_standard
J 0
(-7650 3325);
DISPLAY 0.723404 (-7650 3325);
PAINT MONO (-7650 3325);
DISPLAY INVISIBLE (-7650 3325);
FORCEPROP 1 LAST BODY_TYPE PLUMBING
J 2
(-7650 3375);
DISPLAY 0.872340 (-7650 3375);
PAINT GREEN (-7650 3375);
DISPLAY INVISIBLE (-7650 3375);
FORCEPROP 1 LAST HDL_TAP TRUE
J 2
(-7975 3200);
DISPLAY 0.872340 (-7975 3200);
DISPLAY INVISIBLE (-7975 3200);
FORCEPROP 1 LAST PATH I27
J 2
(-7648 3325);
DISPLAY 0.872340 (-7648 3325);
PAINT GREEN (-7648 3325);
DISPLAY INVISIBLE (-7648 3325);
FORCEADD TAP..1
R 2
(-7650 3375);
FORCEPROP 3 LASTPIN (-7600 3375) SIG_NAME M_J_CPU0_SB_CB<5>
J 0
(-7590 3385);
DISPLAY 0.659574 (-7590 3385);
PAINT MONO (-7590 3385);
DISPLAY INVISIBLE (-7590 3385);
FORCEPROP 1 LASTPIN (-7600 3375) BN 5
J 2
(-7588 3383);
DISPLAY 0.489362 (-7588 3383);
PAINT GREEN (-7588 3383);
FORCEPROP 2 LAST CDS_LIB mstr_standard
J 0
(-7650 3375);
DISPLAY 0.723404 (-7650 3375);
PAINT MONO (-7650 3375);
DISPLAY INVISIBLE (-7650 3375);
FORCEPROP 1 LAST BODY_TYPE PLUMBING
J 2
(-7650 3425);
DISPLAY 0.872340 (-7650 3425);
PAINT GREEN (-7650 3425);
DISPLAY INVISIBLE (-7650 3425);
FORCEPROP 1 LAST HDL_TAP TRUE
J 2
(-7975 3250);
DISPLAY 0.872340 (-7975 3250);
DISPLAY INVISIBLE (-7975 3250);
FORCEPROP 1 LAST PATH I28
J 2
(-7648 3375);
DISPLAY 0.872340 (-7648 3375);
PAINT GREEN (-7648 3375);
DISPLAY INVISIBLE (-7648 3375);
FORCEADD TAP..1
R 2
(-7650 3425);
FORCEPROP 3 LASTPIN (-7600 3425) SIG_NAME M_J_CPU0_SB_CB<6>
J 0
(-7590 3435);
DISPLAY 0.659574 (-7590 3435);
PAINT MONO (-7590 3435);
DISPLAY INVISIBLE (-7590 3435);
FORCEPROP 1 LASTPIN (-7600 3425) BN 6
J 2
(-7588 3433);
DISPLAY 0.489362 (-7588 3433);
PAINT GREEN (-7588 3433);
FORCEPROP 2 LAST CDS_LIB mstr_standard
J 0
(-7650 3425);
DISPLAY 0.723404 (-7650 3425);
PAINT MONO (-7650 3425);
DISPLAY INVISIBLE (-7650 3425);
FORCEPROP 1 LAST BODY_TYPE PLUMBING
J 2
(-7650 3475);
DISPLAY 0.872340 (-7650 3475);
PAINT GREEN (-7650 3475);
DISPLAY INVISIBLE (-7650 3475);
FORCEPROP 1 LAST HDL_TAP TRUE
J 2
(-7975 3300);
DISPLAY 0.872340 (-7975 3300);
DISPLAY INVISIBLE (-7975 3300);
FORCEPROP 1 LAST PATH I29
J 2
(-7648 3425);
DISPLAY 0.872340 (-7648 3425);
PAINT GREEN (-7648 3425);
DISPLAY INVISIBLE (-7648 3425);
FORCEADD TAP..1
R 2
(-7650 3475);
FORCEPROP 3 LASTPIN (-7600 3475) SIG_NAME M_J_CPU0_SB_CB<7>
J 0
(-7590 3485);
DISPLAY 0.659574 (-7590 3485);
PAINT MONO (-7590 3485);
DISPLAY INVISIBLE (-7590 3485);
FORCEPROP 1 LASTPIN (-7600 3475) BN 7
J 2
(-7588 3483);
DISPLAY 0.489362 (-7588 3483);
PAINT GREEN (-7588 3483);
FORCEPROP 2 LAST CDS_LIB mstr_standard
J 0
(-7650 3475);
DISPLAY 0.723404 (-7650 3475);
PAINT MONO (-7650 3475);
DISPLAY INVISIBLE (-7650 3475);
FORCEPROP 1 LAST BODY_TYPE PLUMBING
J 2
(-7650 3525);
DISPLAY 0.872340 (-7650 3525);
PAINT GREEN (-7650 3525);
DISPLAY INVISIBLE (-7650 3525);
FORCEPROP 1 LAST HDL_TAP TRUE
J 2
(-7975 3350);
DISPLAY 0.872340 (-7975 3350);
DISPLAY INVISIBLE (-7975 3350);
FORCEPROP 1 LAST PATH I30
J 2
(-7648 3475);
DISPLAY 0.872340 (-7648 3475);
PAINT GREEN (-7648 3475);
DISPLAY INVISIBLE (-7648 3475);
FORCEADD TAP..1
R 2
(-7650 3575);
FORCEPROP 3 LASTPIN (-7600 3575) SIG_NAME M_J_CPU0_SA_CB<0>
J 0
(-7590 3585);
DISPLAY 0.659574 (-7590 3585);
PAINT MONO (-7590 3585);
DISPLAY INVISIBLE (-7590 3585);
FORCEPROP 1 LASTPIN (-7600 3575) BN 0
J 2
(-7588 3583);
DISPLAY 0.489362 (-7588 3583);
PAINT GREEN (-7588 3583);
FORCEPROP 2 LAST CDS_LIB mstr_standard
J 0
(-7650 3575);
DISPLAY 0.723404 (-7650 3575);
PAINT MONO (-7650 3575);
DISPLAY INVISIBLE (-7650 3575);
FORCEPROP 1 LAST BODY_TYPE PLUMBING
J 2
(-7650 3625);
DISPLAY 0.872340 (-7650 3625);
PAINT GREEN (-7650 3625);
DISPLAY INVISIBLE (-7650 3625);
FORCEPROP 1 LAST HDL_TAP TRUE
J 2
(-7975 3450);
DISPLAY 0.872340 (-7975 3450);
DISPLAY INVISIBLE (-7975 3450);
FORCEPROP 1 LAST PATH I31
J 2
(-7648 3575);
DISPLAY 0.872340 (-7648 3575);
PAINT GREEN (-7648 3575);
DISPLAY INVISIBLE (-7648 3575);
FORCEADD TAP..1
R 2
(-7650 3625);
FORCEPROP 3 LASTPIN (-7600 3625) SIG_NAME M_J_CPU0_SA_CB<1>
J 0
(-7590 3635);
DISPLAY 0.659574 (-7590 3635);
PAINT MONO (-7590 3635);
DISPLAY INVISIBLE (-7590 3635);
FORCEPROP 1 LASTPIN (-7600 3625) BN 1
J 2
(-7588 3633);
DISPLAY 0.489362 (-7588 3633);
PAINT GREEN (-7588 3633);
FORCEPROP 2 LAST CDS_LIB mstr_standard
J 0
(-7650 3625);
DISPLAY 0.723404 (-7650 3625);
PAINT MONO (-7650 3625);
DISPLAY INVISIBLE (-7650 3625);
FORCEPROP 1 LAST BODY_TYPE PLUMBING
J 2
(-7650 3675);
DISPLAY 0.872340 (-7650 3675);
PAINT GREEN (-7650 3675);
DISPLAY INVISIBLE (-7650 3675);
FORCEPROP 1 LAST HDL_TAP TRUE
J 2
(-7975 3500);
DISPLAY 0.872340 (-7975 3500);
DISPLAY INVISIBLE (-7975 3500);
FORCEPROP 1 LAST PATH I32
J 2
(-7648 3625);
DISPLAY 0.872340 (-7648 3625);
PAINT GREEN (-7648 3625);
DISPLAY INVISIBLE (-7648 3625);
FORCEADD TAP..1
R 2
(-7650 3725);
FORCEPROP 3 LASTPIN (-7600 3725) SIG_NAME M_J_CPU0_SA_CB<3>
J 0
(-7590 3735);
DISPLAY 0.659574 (-7590 3735);
PAINT MONO (-7590 3735);
DISPLAY INVISIBLE (-7590 3735);
FORCEPROP 1 LASTPIN (-7600 3725) BN 3
J 2
(-7588 3733);
DISPLAY 0.489362 (-7588 3733);
PAINT GREEN (-7588 3733);
FORCEPROP 2 LAST CDS_LIB mstr_standard
J 0
(-7650 3725);
DISPLAY 0.723404 (-7650 3725);
PAINT MONO (-7650 3725);
DISPLAY INVISIBLE (-7650 3725);
FORCEPROP 1 LAST BODY_TYPE PLUMBING
J 2
(-7650 3775);
DISPLAY 0.872340 (-7650 3775);
PAINT GREEN (-7650 3775);
DISPLAY INVISIBLE (-7650 3775);
FORCEPROP 1 LAST HDL_TAP TRUE
J 2
(-7975 3600);
DISPLAY 0.872340 (-7975 3600);
DISPLAY INVISIBLE (-7975 3600);
FORCEPROP 1 LAST PATH I33
J 2
(-7648 3725);
DISPLAY 0.872340 (-7648 3725);
PAINT GREEN (-7648 3725);
DISPLAY INVISIBLE (-7648 3725);
FORCEADD TAP..1
R 2
(-7650 3675);
FORCEPROP 3 LASTPIN (-7600 3675) SIG_NAME M_J_CPU0_SA_CB<2>
J 0
(-7590 3685);
DISPLAY 0.659574 (-7590 3685);
PAINT MONO (-7590 3685);
DISPLAY INVISIBLE (-7590 3685);
FORCEPROP 1 LASTPIN (-7600 3675) BN 2
J 2
(-7588 3683);
DISPLAY 0.489362 (-7588 3683);
PAINT GREEN (-7588 3683);
FORCEPROP 2 LAST CDS_LIB mstr_standard
J 0
(-7650 3675);
DISPLAY 0.723404 (-7650 3675);
PAINT MONO (-7650 3675);
DISPLAY INVISIBLE (-7650 3675);
FORCEPROP 1 LAST BODY_TYPE PLUMBING
J 2
(-7650 3725);
DISPLAY 0.872340 (-7650 3725);
PAINT GREEN (-7650 3725);
DISPLAY INVISIBLE (-7650 3725);
FORCEPROP 1 LAST HDL_TAP TRUE
J 2
(-7975 3550);
DISPLAY 0.872340 (-7975 3550);
DISPLAY INVISIBLE (-7975 3550);
FORCEPROP 1 LAST PATH I34
J 2
(-7648 3675);
DISPLAY 0.872340 (-7648 3675);
PAINT GREEN (-7648 3675);
DISPLAY INVISIBLE (-7648 3675);
FORCEADD TAP..1
(-5950 2125);
FORCEPROP 3 LASTPIN (-6000 2125) SIG_NAME M_J_CPU0_SB_DQ<0>
J 0
(-5990 2135);
DISPLAY 0.659574 (-5990 2135);
PAINT MONO (-5990 2135);
DISPLAY INVISIBLE (-5990 2135);
FORCEPROP 1 LASTPIN (-6000 2125) BN 0
J 0
(-6012 2133);
DISPLAY 0.489362 (-6012 2133);
PAINT GREEN (-6012 2133);
FORCEPROP 2 LAST CDS_LIB mstr_standard
J 0
(-5950 2125);
DISPLAY 0.723404 (-5950 2125);
PAINT MONO (-5950 2125);
DISPLAY INVISIBLE (-5950 2125);
FORCEPROP 1 LAST BODY_TYPE PLUMBING
J 0
(-5950 2175);
DISPLAY 0.872340 (-5950 2175);
PAINT GREEN (-5950 2175);
DISPLAY INVISIBLE (-5950 2175);
FORCEPROP 1 LAST HDL_TAP TRUE
J 0
(-5625 2000);
DISPLAY 0.872340 (-5625 2000);
DISPLAY INVISIBLE (-5625 2000);
FORCEPROP 1 LAST PATH I35
J 0
(-5952 2125);
DISPLAY 0.872340 (-5952 2125);
PAINT GREEN (-5952 2125);
DISPLAY INVISIBLE (-5952 2125);
FORCEADD TAP..1
(-5950 2225);
FORCEPROP 3 LASTPIN (-6000 2225) SIG_NAME M_J_CPU0_SB_DQ<2>
J 0
(-5990 2235);
DISPLAY 0.659574 (-5990 2235);
PAINT MONO (-5990 2235);
DISPLAY INVISIBLE (-5990 2235);
FORCEPROP 1 LASTPIN (-6000 2225) BN 2
J 0
(-6012 2233);
DISPLAY 0.489362 (-6012 2233);
PAINT GREEN (-6012 2233);
FORCEPROP 2 LAST CDS_LIB mstr_standard
J 0
(-5950 2225);
DISPLAY 0.723404 (-5950 2225);
PAINT MONO (-5950 2225);
DISPLAY INVISIBLE (-5950 2225);
FORCEPROP 1 LAST BODY_TYPE PLUMBING
J 0
(-5950 2275);
DISPLAY 0.872340 (-5950 2275);
PAINT GREEN (-5950 2275);
DISPLAY INVISIBLE (-5950 2275);
FORCEPROP 1 LAST HDL_TAP TRUE
J 0
(-5625 2100);
DISPLAY 0.872340 (-5625 2100);
DISPLAY INVISIBLE (-5625 2100);
FORCEPROP 1 LAST PATH I36
J 0
(-5952 2225);
DISPLAY 0.872340 (-5952 2225);
PAINT GREEN (-5952 2225);
DISPLAY INVISIBLE (-5952 2225);
FORCEADD TAP..1
(-5950 2175);
FORCEPROP 3 LASTPIN (-6000 2175) SIG_NAME M_J_CPU0_SB_DQ<1>
J 0
(-5990 2185);
DISPLAY 0.659574 (-5990 2185);
PAINT MONO (-5990 2185);
DISPLAY INVISIBLE (-5990 2185);
FORCEPROP 1 LASTPIN (-6000 2175) BN 1
J 0
(-6012 2183);
DISPLAY 0.489362 (-6012 2183);
PAINT GREEN (-6012 2183);
FORCEPROP 2 LAST CDS_LIB mstr_standard
J 0
(-5950 2175);
DISPLAY 0.723404 (-5950 2175);
PAINT MONO (-5950 2175);
DISPLAY INVISIBLE (-5950 2175);
FORCEPROP 1 LAST BODY_TYPE PLUMBING
J 0
(-5950 2225);
DISPLAY 0.872340 (-5950 2225);
PAINT GREEN (-5950 2225);
DISPLAY INVISIBLE (-5950 2225);
FORCEPROP 1 LAST HDL_TAP TRUE
J 0
(-5625 2050);
DISPLAY 0.872340 (-5625 2050);
DISPLAY INVISIBLE (-5625 2050);
FORCEPROP 1 LAST PATH I37
J 0
(-5952 2175);
DISPLAY 0.872340 (-5952 2175);
PAINT GREEN (-5952 2175);
DISPLAY INVISIBLE (-5952 2175);
FORCEADD TAP..1
(-5950 2325);
FORCEPROP 3 LASTPIN (-6000 2325) SIG_NAME M_J_CPU0_SB_DQ<4>
J 0
(-5990 2335);
DISPLAY 0.659574 (-5990 2335);
PAINT MONO (-5990 2335);
DISPLAY INVISIBLE (-5990 2335);
FORCEPROP 1 LASTPIN (-6000 2325) BN 4
J 0
(-6012 2333);
DISPLAY 0.489362 (-6012 2333);
PAINT GREEN (-6012 2333);
FORCEPROP 2 LAST CDS_LIB mstr_standard
J 0
(-5950 2325);
DISPLAY 0.723404 (-5950 2325);
PAINT MONO (-5950 2325);
DISPLAY INVISIBLE (-5950 2325);
FORCEPROP 1 LAST BODY_TYPE PLUMBING
J 0
(-5950 2375);
DISPLAY 0.872340 (-5950 2375);
PAINT GREEN (-5950 2375);
DISPLAY INVISIBLE (-5950 2375);
FORCEPROP 1 LAST HDL_TAP TRUE
J 0
(-5625 2200);
DISPLAY 0.872340 (-5625 2200);
DISPLAY INVISIBLE (-5625 2200);
FORCEPROP 1 LAST PATH I38
J 0
(-5952 2325);
DISPLAY 0.872340 (-5952 2325);
PAINT GREEN (-5952 2325);
DISPLAY INVISIBLE (-5952 2325);
FORCEADD TAP..1
(-5950 2275);
FORCEPROP 3 LASTPIN (-6000 2275) SIG_NAME M_J_CPU0_SB_DQ<3>
J 0
(-5990 2285);
DISPLAY 0.659574 (-5990 2285);
PAINT MONO (-5990 2285);
DISPLAY INVISIBLE (-5990 2285);
FORCEPROP 1 LASTPIN (-6000 2275) BN 3
J 0
(-6012 2283);
DISPLAY 0.489362 (-6012 2283);
PAINT GREEN (-6012 2283);
FORCEPROP 2 LAST CDS_LIB mstr_standard
J 0
(-5950 2275);
DISPLAY 0.723404 (-5950 2275);
PAINT MONO (-5950 2275);
DISPLAY INVISIBLE (-5950 2275);
FORCEPROP 1 LAST BODY_TYPE PLUMBING
J 0
(-5950 2325);
DISPLAY 0.872340 (-5950 2325);
PAINT GREEN (-5950 2325);
DISPLAY INVISIBLE (-5950 2325);
FORCEPROP 1 LAST HDL_TAP TRUE
J 0
(-5625 2150);
DISPLAY 0.872340 (-5625 2150);
DISPLAY INVISIBLE (-5625 2150);
FORCEPROP 1 LAST PATH I39
J 0
(-5952 2275);
DISPLAY 0.872340 (-5952 2275);
PAINT GREEN (-5952 2275);
DISPLAY INVISIBLE (-5952 2275);
FORCEADD TAP..1
(-5950 2375);
FORCEPROP 3 LASTPIN (-6000 2375) SIG_NAME M_J_CPU0_SB_DQ<5>
J 0
(-5990 2385);
DISPLAY 0.659574 (-5990 2385);
PAINT MONO (-5990 2385);
DISPLAY INVISIBLE (-5990 2385);
FORCEPROP 1 LASTPIN (-6000 2375) BN 5
J 0
(-6012 2383);
DISPLAY 0.489362 (-6012 2383);
PAINT GREEN (-6012 2383);
FORCEPROP 2 LAST CDS_LIB mstr_standard
J 0
(-5950 2375);
DISPLAY 0.723404 (-5950 2375);
PAINT MONO (-5950 2375);
DISPLAY INVISIBLE (-5950 2375);
FORCEPROP 1 LAST BODY_TYPE PLUMBING
J 0
(-5950 2425);
DISPLAY 0.872340 (-5950 2425);
PAINT GREEN (-5950 2425);
DISPLAY INVISIBLE (-5950 2425);
FORCEPROP 1 LAST HDL_TAP TRUE
J 0
(-5625 2250);
DISPLAY 0.872340 (-5625 2250);
DISPLAY INVISIBLE (-5625 2250);
FORCEPROP 1 LAST PATH I40
J 0
(-5952 2375);
DISPLAY 0.872340 (-5952 2375);
PAINT GREEN (-5952 2375);
DISPLAY INVISIBLE (-5952 2375);
FORCEADD TAP..1
(-5950 2425);
FORCEPROP 3 LASTPIN (-6000 2425) SIG_NAME M_J_CPU0_SB_DQ<6>
J 0
(-5990 2435);
DISPLAY 0.659574 (-5990 2435);
PAINT MONO (-5990 2435);
DISPLAY INVISIBLE (-5990 2435);
FORCEPROP 1 LASTPIN (-6000 2425) BN 6
J 0
(-6012 2433);
DISPLAY 0.489362 (-6012 2433);
PAINT GREEN (-6012 2433);
FORCEPROP 2 LAST CDS_LIB mstr_standard
J 0
(-5950 2425);
DISPLAY 0.723404 (-5950 2425);
PAINT MONO (-5950 2425);
DISPLAY INVISIBLE (-5950 2425);
FORCEPROP 1 LAST BODY_TYPE PLUMBING
J 0
(-5950 2475);
DISPLAY 0.872340 (-5950 2475);
PAINT GREEN (-5950 2475);
DISPLAY INVISIBLE (-5950 2475);
FORCEPROP 1 LAST HDL_TAP TRUE
J 0
(-5625 2300);
DISPLAY 0.872340 (-5625 2300);
DISPLAY INVISIBLE (-5625 2300);
FORCEPROP 1 LAST PATH I41
J 0
(-5952 2425);
DISPLAY 0.872340 (-5952 2425);
PAINT GREEN (-5952 2425);
DISPLAY INVISIBLE (-5952 2425);
FORCEADD TAP..1
(-5950 2475);
FORCEPROP 3 LASTPIN (-6000 2475) SIG_NAME M_J_CPU0_SB_DQ<7>
J 0
(-5990 2485);
DISPLAY 0.659574 (-5990 2485);
PAINT MONO (-5990 2485);
DISPLAY INVISIBLE (-5990 2485);
FORCEPROP 1 LASTPIN (-6000 2475) BN 7
J 0
(-6012 2483);
DISPLAY 0.489362 (-6012 2483);
PAINT GREEN (-6012 2483);
FORCEPROP 2 LAST CDS_LIB mstr_standard
J 0
(-5950 2475);
DISPLAY 0.723404 (-5950 2475);
PAINT MONO (-5950 2475);
DISPLAY INVISIBLE (-5950 2475);
FORCEPROP 1 LAST BODY_TYPE PLUMBING
J 0
(-5950 2525);
DISPLAY 0.872340 (-5950 2525);
PAINT GREEN (-5950 2525);
DISPLAY INVISIBLE (-5950 2525);
FORCEPROP 1 LAST HDL_TAP TRUE
J 0
(-5625 2350);
DISPLAY 0.872340 (-5625 2350);
DISPLAY INVISIBLE (-5625 2350);
FORCEPROP 1 LAST PATH I42
J 0
(-5952 2475);
DISPLAY 0.872340 (-5952 2475);
PAINT GREEN (-5952 2475);
DISPLAY INVISIBLE (-5952 2475);
FORCEADD TAP..1
(-5950 2575);
FORCEPROP 3 LASTPIN (-6000 2575) SIG_NAME M_J_CPU0_SB_DQ<9>
J 0
(-5990 2585);
DISPLAY 0.659574 (-5990 2585);
PAINT MONO (-5990 2585);
DISPLAY INVISIBLE (-5990 2585);
FORCEPROP 1 LASTPIN (-6000 2575) BN 9
J 0
(-6012 2583);
DISPLAY 0.489362 (-6012 2583);
PAINT GREEN (-6012 2583);
FORCEPROP 2 LAST CDS_LIB mstr_standard
J 0
(-5950 2575);
DISPLAY 0.723404 (-5950 2575);
PAINT MONO (-5950 2575);
DISPLAY INVISIBLE (-5950 2575);
FORCEPROP 1 LAST BODY_TYPE PLUMBING
J 0
(-5950 2625);
DISPLAY 0.872340 (-5950 2625);
PAINT GREEN (-5950 2625);
DISPLAY INVISIBLE (-5950 2625);
FORCEPROP 1 LAST HDL_TAP TRUE
J 0
(-5625 2450);
DISPLAY 0.872340 (-5625 2450);
DISPLAY INVISIBLE (-5625 2450);
FORCEPROP 1 LAST PATH I43
J 0
(-5952 2575);
DISPLAY 0.872340 (-5952 2575);
PAINT GREEN (-5952 2575);
DISPLAY INVISIBLE (-5952 2575);
FORCEADD TAP..1
(-5950 2525);
FORCEPROP 3 LASTPIN (-6000 2525) SIG_NAME M_J_CPU0_SB_DQ<8>
J 0
(-5990 2535);
DISPLAY 0.659574 (-5990 2535);
PAINT MONO (-5990 2535);
DISPLAY INVISIBLE (-5990 2535);
FORCEPROP 1 LASTPIN (-6000 2525) BN 8
J 0
(-6012 2533);
DISPLAY 0.489362 (-6012 2533);
PAINT GREEN (-6012 2533);
FORCEPROP 2 LAST CDS_LIB mstr_standard
J 0
(-5950 2525);
DISPLAY 0.723404 (-5950 2525);
PAINT MONO (-5950 2525);
DISPLAY INVISIBLE (-5950 2525);
FORCEPROP 1 LAST BODY_TYPE PLUMBING
J 0
(-5950 2575);
DISPLAY 0.872340 (-5950 2575);
PAINT GREEN (-5950 2575);
DISPLAY INVISIBLE (-5950 2575);
FORCEPROP 1 LAST HDL_TAP TRUE
J 0
(-5625 2400);
DISPLAY 0.872340 (-5625 2400);
DISPLAY INVISIBLE (-5625 2400);
FORCEPROP 1 LAST PATH I44
J 0
(-5952 2525);
DISPLAY 0.872340 (-5952 2525);
PAINT GREEN (-5952 2525);
DISPLAY INVISIBLE (-5952 2525);
FORCEADD TAP..1
(-5950 2625);
FORCEPROP 3 LASTPIN (-6000 2625) SIG_NAME M_J_CPU0_SB_DQ<10>
J 0
(-5990 2635);
DISPLAY 0.659574 (-5990 2635);
PAINT MONO (-5990 2635);
DISPLAY INVISIBLE (-5990 2635);
FORCEPROP 1 LASTPIN (-6000 2625) BN 10
J 0
(-6012 2633);
DISPLAY 0.489362 (-6012 2633);
PAINT GREEN (-6012 2633);
FORCEPROP 2 LAST CDS_LIB mstr_standard
J 0
(-5950 2625);
DISPLAY 0.723404 (-5950 2625);
PAINT MONO (-5950 2625);
DISPLAY INVISIBLE (-5950 2625);
FORCEPROP 1 LAST BODY_TYPE PLUMBING
J 0
(-5950 2675);
DISPLAY 0.872340 (-5950 2675);
PAINT GREEN (-5950 2675);
DISPLAY INVISIBLE (-5950 2675);
FORCEPROP 1 LAST HDL_TAP TRUE
J 0
(-5625 2500);
DISPLAY 0.872340 (-5625 2500);
DISPLAY INVISIBLE (-5625 2500);
FORCEPROP 1 LAST PATH I45
J 0
(-5952 2625);
DISPLAY 0.872340 (-5952 2625);
PAINT GREEN (-5952 2625);
DISPLAY INVISIBLE (-5952 2625);
FORCEADD TAP..1
(-5950 2725);
FORCEPROP 3 LASTPIN (-6000 2725) SIG_NAME M_J_CPU0_SB_DQ<12>
J 0
(-5990 2735);
DISPLAY 0.659574 (-5990 2735);
PAINT MONO (-5990 2735);
DISPLAY INVISIBLE (-5990 2735);
FORCEPROP 1 LASTPIN (-6000 2725) BN 12
J 0
(-6012 2733);
DISPLAY 0.489362 (-6012 2733);
PAINT GREEN (-6012 2733);
FORCEPROP 2 LAST CDS_LIB mstr_standard
J 0
(-5950 2725);
DISPLAY 0.723404 (-5950 2725);
PAINT MONO (-5950 2725);
DISPLAY INVISIBLE (-5950 2725);
FORCEPROP 1 LAST BODY_TYPE PLUMBING
J 0
(-5950 2775);
DISPLAY 0.872340 (-5950 2775);
PAINT GREEN (-5950 2775);
DISPLAY INVISIBLE (-5950 2775);
FORCEPROP 1 LAST HDL_TAP TRUE
J 0
(-5625 2600);
DISPLAY 0.872340 (-5625 2600);
DISPLAY INVISIBLE (-5625 2600);
FORCEPROP 1 LAST PATH I46
J 0
(-5952 2725);
DISPLAY 0.872340 (-5952 2725);
PAINT GREEN (-5952 2725);
DISPLAY INVISIBLE (-5952 2725);
FORCEADD TAP..1
(-5950 2675);
FORCEPROP 3 LASTPIN (-6000 2675) SIG_NAME M_J_CPU0_SB_DQ<11>
J 0
(-5990 2685);
DISPLAY 0.659574 (-5990 2685);
PAINT MONO (-5990 2685);
DISPLAY INVISIBLE (-5990 2685);
FORCEPROP 1 LASTPIN (-6000 2675) BN 11
J 0
(-6012 2683);
DISPLAY 0.489362 (-6012 2683);
PAINT GREEN (-6012 2683);
FORCEPROP 2 LAST CDS_LIB mstr_standard
J 0
(-5950 2675);
DISPLAY 0.723404 (-5950 2675);
PAINT MONO (-5950 2675);
DISPLAY INVISIBLE (-5950 2675);
FORCEPROP 1 LAST BODY_TYPE PLUMBING
J 0
(-5950 2725);
DISPLAY 0.872340 (-5950 2725);
PAINT GREEN (-5950 2725);
DISPLAY INVISIBLE (-5950 2725);
FORCEPROP 1 LAST HDL_TAP TRUE
J 0
(-5625 2550);
DISPLAY 0.872340 (-5625 2550);
DISPLAY INVISIBLE (-5625 2550);
FORCEPROP 1 LAST PATH I47
J 0
(-5952 2675);
DISPLAY 0.872340 (-5952 2675);
PAINT GREEN (-5952 2675);
DISPLAY INVISIBLE (-5952 2675);
FORCEADD TAP..1
(-5950 2825);
FORCEPROP 3 LASTPIN (-6000 2825) SIG_NAME M_J_CPU0_SB_DQ<14>
J 0
(-5990 2835);
DISPLAY 0.659574 (-5990 2835);
PAINT MONO (-5990 2835);
DISPLAY INVISIBLE (-5990 2835);
FORCEPROP 1 LASTPIN (-6000 2825) BN 14
J 0
(-6012 2833);
DISPLAY 0.489362 (-6012 2833);
PAINT GREEN (-6012 2833);
FORCEPROP 2 LAST CDS_LIB mstr_standard
J 0
(-5950 2825);
DISPLAY 0.723404 (-5950 2825);
PAINT MONO (-5950 2825);
DISPLAY INVISIBLE (-5950 2825);
FORCEPROP 1 LAST BODY_TYPE PLUMBING
J 0
(-5950 2875);
DISPLAY 0.872340 (-5950 2875);
PAINT GREEN (-5950 2875);
DISPLAY INVISIBLE (-5950 2875);
FORCEPROP 1 LAST HDL_TAP TRUE
J 0
(-5625 2700);
DISPLAY 0.872340 (-5625 2700);
DISPLAY INVISIBLE (-5625 2700);
FORCEPROP 1 LAST PATH I48
J 0
(-5952 2825);
DISPLAY 0.872340 (-5952 2825);
PAINT GREEN (-5952 2825);
DISPLAY INVISIBLE (-5952 2825);
FORCEADD TAP..1
(-5950 2775);
FORCEPROP 3 LASTPIN (-6000 2775) SIG_NAME M_J_CPU0_SB_DQ<13>
J 0
(-5990 2785);
DISPLAY 0.659574 (-5990 2785);
PAINT MONO (-5990 2785);
DISPLAY INVISIBLE (-5990 2785);
FORCEPROP 1 LASTPIN (-6000 2775) BN 13
J 0
(-6012 2783);
DISPLAY 0.489362 (-6012 2783);
PAINT GREEN (-6012 2783);
FORCEPROP 2 LAST CDS_LIB mstr_standard
J 0
(-5950 2775);
DISPLAY 0.723404 (-5950 2775);
PAINT MONO (-5950 2775);
DISPLAY INVISIBLE (-5950 2775);
FORCEPROP 1 LAST BODY_TYPE PLUMBING
J 0
(-5950 2825);
DISPLAY 0.872340 (-5950 2825);
PAINT GREEN (-5950 2825);
DISPLAY INVISIBLE (-5950 2825);
FORCEPROP 1 LAST HDL_TAP TRUE
J 0
(-5625 2650);
DISPLAY 0.872340 (-5625 2650);
DISPLAY INVISIBLE (-5625 2650);
FORCEPROP 1 LAST PATH I49
J 0
(-5952 2775);
DISPLAY 0.872340 (-5952 2775);
PAINT GREEN (-5952 2775);
DISPLAY INVISIBLE (-5952 2775);
FORCEADD TAP..1
(-5950 2875);
FORCEPROP 3 LASTPIN (-6000 2875) SIG_NAME M_J_CPU0_SB_DQ<15>
J 0
(-5990 2885);
DISPLAY 0.659574 (-5990 2885);
PAINT MONO (-5990 2885);
DISPLAY INVISIBLE (-5990 2885);
FORCEPROP 1 LASTPIN (-6000 2875) BN 15
J 0
(-6012 2883);
DISPLAY 0.489362 (-6012 2883);
PAINT GREEN (-6012 2883);
FORCEPROP 2 LAST CDS_LIB mstr_standard
J 0
(-5950 2875);
DISPLAY 0.723404 (-5950 2875);
PAINT MONO (-5950 2875);
DISPLAY INVISIBLE (-5950 2875);
FORCEPROP 1 LAST BODY_TYPE PLUMBING
J 0
(-5950 2925);
DISPLAY 0.872340 (-5950 2925);
PAINT GREEN (-5950 2925);
DISPLAY INVISIBLE (-5950 2925);
FORCEPROP 1 LAST HDL_TAP TRUE
J 0
(-5625 2750);
DISPLAY 0.872340 (-5625 2750);
DISPLAY INVISIBLE (-5625 2750);
FORCEPROP 1 LAST PATH I50
J 0
(-5952 2875);
DISPLAY 0.872340 (-5952 2875);
PAINT GREEN (-5952 2875);
DISPLAY INVISIBLE (-5952 2875);
FORCEADD TAP..1
(-5950 2975);
FORCEPROP 3 LASTPIN (-6000 2975) SIG_NAME M_J_CPU0_SB_DQ<17>
J 0
(-5990 2985);
DISPLAY 0.659574 (-5990 2985);
PAINT MONO (-5990 2985);
DISPLAY INVISIBLE (-5990 2985);
FORCEPROP 1 LASTPIN (-6000 2975) BN 17
J 0
(-6012 2983);
DISPLAY 0.489362 (-6012 2983);
PAINT GREEN (-6012 2983);
FORCEPROP 2 LAST CDS_LIB mstr_standard
J 0
(-5950 2975);
DISPLAY 0.723404 (-5950 2975);
PAINT MONO (-5950 2975);
DISPLAY INVISIBLE (-5950 2975);
FORCEPROP 1 LAST BODY_TYPE PLUMBING
J 0
(-5950 3025);
DISPLAY 0.872340 (-5950 3025);
PAINT GREEN (-5950 3025);
DISPLAY INVISIBLE (-5950 3025);
FORCEPROP 1 LAST HDL_TAP TRUE
J 0
(-5625 2850);
DISPLAY 0.872340 (-5625 2850);
DISPLAY INVISIBLE (-5625 2850);
FORCEPROP 1 LAST PATH I51
J 0
(-5952 2975);
DISPLAY 0.872340 (-5952 2975);
PAINT GREEN (-5952 2975);
DISPLAY INVISIBLE (-5952 2975);
FORCEADD TAP..1
(-5950 2925);
FORCEPROP 3 LASTPIN (-6000 2925) SIG_NAME M_J_CPU0_SB_DQ<16>
J 0
(-5990 2935);
DISPLAY 0.659574 (-5990 2935);
PAINT MONO (-5990 2935);
DISPLAY INVISIBLE (-5990 2935);
FORCEPROP 1 LASTPIN (-6000 2925) BN 16
J 0
(-6012 2933);
DISPLAY 0.489362 (-6012 2933);
PAINT GREEN (-6012 2933);
FORCEPROP 2 LAST CDS_LIB mstr_standard
J 0
(-5950 2925);
DISPLAY 0.723404 (-5950 2925);
PAINT MONO (-5950 2925);
DISPLAY INVISIBLE (-5950 2925);
FORCEPROP 1 LAST BODY_TYPE PLUMBING
J 0
(-5950 2975);
DISPLAY 0.872340 (-5950 2975);
PAINT GREEN (-5950 2975);
DISPLAY INVISIBLE (-5950 2975);
FORCEPROP 1 LAST HDL_TAP TRUE
J 0
(-5625 2800);
DISPLAY 0.872340 (-5625 2800);
DISPLAY INVISIBLE (-5625 2800);
FORCEPROP 1 LAST PATH I52
J 0
(-5952 2925);
DISPLAY 0.872340 (-5952 2925);
PAINT GREEN (-5952 2925);
DISPLAY INVISIBLE (-5952 2925);
FORCEADD TAP..1
(-5950 3125);
FORCEPROP 3 LASTPIN (-6000 3125) SIG_NAME M_J_CPU0_SB_DQ<20>
J 0
(-5990 3135);
DISPLAY 0.659574 (-5990 3135);
PAINT MONO (-5990 3135);
DISPLAY INVISIBLE (-5990 3135);
FORCEPROP 1 LASTPIN (-6000 3125) BN 20
J 0
(-6012 3133);
DISPLAY 0.489362 (-6012 3133);
PAINT GREEN (-6012 3133);
FORCEPROP 2 LAST CDS_LIB mstr_standard
J 0
(-5950 3125);
DISPLAY 0.723404 (-5950 3125);
PAINT MONO (-5950 3125);
DISPLAY INVISIBLE (-5950 3125);
FORCEPROP 1 LAST BODY_TYPE PLUMBING
J 0
(-5950 3175);
DISPLAY 0.872340 (-5950 3175);
PAINT GREEN (-5950 3175);
DISPLAY INVISIBLE (-5950 3175);
FORCEPROP 1 LAST HDL_TAP TRUE
J 0
(-5625 3000);
DISPLAY 0.872340 (-5625 3000);
DISPLAY INVISIBLE (-5625 3000);
FORCEPROP 1 LAST PATH I53
J 0
(-5952 3125);
DISPLAY 0.872340 (-5952 3125);
PAINT GREEN (-5952 3125);
DISPLAY INVISIBLE (-5952 3125);
FORCEADD TAP..1
(-5950 3075);
FORCEPROP 3 LASTPIN (-6000 3075) SIG_NAME M_J_CPU0_SB_DQ<19>
J 0
(-5990 3085);
DISPLAY 0.659574 (-5990 3085);
PAINT MONO (-5990 3085);
DISPLAY INVISIBLE (-5990 3085);
FORCEPROP 1 LASTPIN (-6000 3075) BN 19
J 0
(-6012 3083);
DISPLAY 0.489362 (-6012 3083);
PAINT GREEN (-6012 3083);
FORCEPROP 2 LAST CDS_LIB mstr_standard
J 0
(-5950 3075);
DISPLAY 0.723404 (-5950 3075);
PAINT MONO (-5950 3075);
DISPLAY INVISIBLE (-5950 3075);
FORCEPROP 1 LAST BODY_TYPE PLUMBING
J 0
(-5950 3125);
DISPLAY 0.872340 (-5950 3125);
PAINT GREEN (-5950 3125);
DISPLAY INVISIBLE (-5950 3125);
FORCEPROP 1 LAST HDL_TAP TRUE
J 0
(-5625 2950);
DISPLAY 0.872340 (-5625 2950);
DISPLAY INVISIBLE (-5625 2950);
FORCEPROP 1 LAST PATH I54
J 0
(-5952 3075);
DISPLAY 0.872340 (-5952 3075);
PAINT GREEN (-5952 3075);
DISPLAY INVISIBLE (-5952 3075);
FORCEADD TAP..1
(-5950 3025);
FORCEPROP 3 LASTPIN (-6000 3025) SIG_NAME M_J_CPU0_SB_DQ<18>
J 0
(-5990 3035);
DISPLAY 0.659574 (-5990 3035);
PAINT MONO (-5990 3035);
DISPLAY INVISIBLE (-5990 3035);
FORCEPROP 1 LASTPIN (-6000 3025) BN 18
J 0
(-6012 3033);
DISPLAY 0.489362 (-6012 3033);
PAINT GREEN (-6012 3033);
FORCEPROP 2 LAST CDS_LIB mstr_standard
J 0
(-5950 3025);
DISPLAY 0.723404 (-5950 3025);
PAINT MONO (-5950 3025);
DISPLAY INVISIBLE (-5950 3025);
FORCEPROP 1 LAST BODY_TYPE PLUMBING
J 0
(-5950 3075);
DISPLAY 0.872340 (-5950 3075);
PAINT GREEN (-5950 3075);
DISPLAY INVISIBLE (-5950 3075);
FORCEPROP 1 LAST HDL_TAP TRUE
J 0
(-5625 2900);
DISPLAY 0.872340 (-5625 2900);
DISPLAY INVISIBLE (-5625 2900);
FORCEPROP 1 LAST PATH I55
J 0
(-5952 3025);
DISPLAY 0.872340 (-5952 3025);
PAINT GREEN (-5952 3025);
DISPLAY INVISIBLE (-5952 3025);
FORCEADD TAP..1
(-5950 3175);
FORCEPROP 3 LASTPIN (-6000 3175) SIG_NAME M_J_CPU0_SB_DQ<21>
J 0
(-5990 3185);
DISPLAY 0.659574 (-5990 3185);
PAINT MONO (-5990 3185);
DISPLAY INVISIBLE (-5990 3185);
FORCEPROP 1 LASTPIN (-6000 3175) BN 21
J 0
(-6012 3183);
DISPLAY 0.489362 (-6012 3183);
PAINT GREEN (-6012 3183);
FORCEPROP 2 LAST CDS_LIB mstr_standard
J 0
(-5950 3175);
DISPLAY 0.723404 (-5950 3175);
PAINT MONO (-5950 3175);
DISPLAY INVISIBLE (-5950 3175);
FORCEPROP 1 LAST BODY_TYPE PLUMBING
J 0
(-5950 3225);
DISPLAY 0.872340 (-5950 3225);
PAINT GREEN (-5950 3225);
DISPLAY INVISIBLE (-5950 3225);
FORCEPROP 1 LAST HDL_TAP TRUE
J 0
(-5625 3050);
DISPLAY 0.872340 (-5625 3050);
DISPLAY INVISIBLE (-5625 3050);
FORCEPROP 1 LAST PATH I56
J 0
(-5952 3175);
DISPLAY 0.872340 (-5952 3175);
PAINT GREEN (-5952 3175);
DISPLAY INVISIBLE (-5952 3175);
FORCEADD TAP..1
(-5950 3225);
FORCEPROP 3 LASTPIN (-6000 3225) SIG_NAME M_J_CPU0_SB_DQ<22>
J 0
(-5990 3235);
DISPLAY 0.659574 (-5990 3235);
PAINT MONO (-5990 3235);
DISPLAY INVISIBLE (-5990 3235);
FORCEPROP 1 LASTPIN (-6000 3225) BN 22
J 0
(-6012 3233);
DISPLAY 0.489362 (-6012 3233);
PAINT GREEN (-6012 3233);
FORCEPROP 2 LAST CDS_LIB mstr_standard
J 0
(-5950 3225);
DISPLAY 0.723404 (-5950 3225);
PAINT MONO (-5950 3225);
DISPLAY INVISIBLE (-5950 3225);
FORCEPROP 1 LAST BODY_TYPE PLUMBING
J 0
(-5950 3275);
DISPLAY 0.872340 (-5950 3275);
PAINT GREEN (-5950 3275);
DISPLAY INVISIBLE (-5950 3275);
FORCEPROP 1 LAST HDL_TAP TRUE
J 0
(-5625 3100);
DISPLAY 0.872340 (-5625 3100);
DISPLAY INVISIBLE (-5625 3100);
FORCEPROP 1 LAST PATH I57
J 0
(-5952 3225);
DISPLAY 0.872340 (-5952 3225);
PAINT GREEN (-5952 3225);
DISPLAY INVISIBLE (-5952 3225);
FORCEADD TAP..1
(-5950 3375);
FORCEPROP 3 LASTPIN (-6000 3375) SIG_NAME M_J_CPU0_SB_DQ<25>
J 0
(-5990 3385);
DISPLAY 0.659574 (-5990 3385);
PAINT MONO (-5990 3385);
DISPLAY INVISIBLE (-5990 3385);
FORCEPROP 1 LASTPIN (-6000 3375) BN 25
J 0
(-6012 3383);
DISPLAY 0.489362 (-6012 3383);
PAINT GREEN (-6012 3383);
FORCEPROP 2 LAST CDS_LIB mstr_standard
J 0
(-5950 3375);
DISPLAY 0.723404 (-5950 3375);
PAINT MONO (-5950 3375);
DISPLAY INVISIBLE (-5950 3375);
FORCEPROP 1 LAST BODY_TYPE PLUMBING
J 0
(-5950 3425);
DISPLAY 0.872340 (-5950 3425);
PAINT GREEN (-5950 3425);
DISPLAY INVISIBLE (-5950 3425);
FORCEPROP 1 LAST HDL_TAP TRUE
J 0
(-5625 3250);
DISPLAY 0.872340 (-5625 3250);
DISPLAY INVISIBLE (-5625 3250);
FORCEPROP 1 LAST PATH I58
J 0
(-5952 3375);
DISPLAY 0.872340 (-5952 3375);
PAINT GREEN (-5952 3375);
DISPLAY INVISIBLE (-5952 3375);
FORCEADD TAP..1
(-5950 3325);
FORCEPROP 3 LASTPIN (-6000 3325) SIG_NAME M_J_CPU0_SB_DQ<24>
J 0
(-5990 3335);
DISPLAY 0.659574 (-5990 3335);
PAINT MONO (-5990 3335);
DISPLAY INVISIBLE (-5990 3335);
FORCEPROP 1 LASTPIN (-6000 3325) BN 24
J 0
(-6012 3333);
DISPLAY 0.489362 (-6012 3333);
PAINT GREEN (-6012 3333);
FORCEPROP 2 LAST CDS_LIB mstr_standard
J 0
(-5950 3325);
DISPLAY 0.723404 (-5950 3325);
PAINT MONO (-5950 3325);
DISPLAY INVISIBLE (-5950 3325);
FORCEPROP 1 LAST BODY_TYPE PLUMBING
J 0
(-5950 3375);
DISPLAY 0.872340 (-5950 3375);
PAINT GREEN (-5950 3375);
DISPLAY INVISIBLE (-5950 3375);
FORCEPROP 1 LAST HDL_TAP TRUE
J 0
(-5625 3200);
DISPLAY 0.872340 (-5625 3200);
DISPLAY INVISIBLE (-5625 3200);
FORCEPROP 1 LAST PATH I59
J 0
(-5952 3325);
DISPLAY 0.872340 (-5952 3325);
PAINT GREEN (-5952 3325);
DISPLAY INVISIBLE (-5952 3325);
FORCEADD OFFPAGE..1
(-8250 2825);
FORCEPROP 2 LAST $XR0 94 
J 0
(-8501 2825);
DISPLAY 0.638298 (-8501 2825);
PAINT MONO (-8501 2825);
FORCEPROP 2 LAST PATH I6
J 0
(-8500 2875);
DISPLAY 1.021277 (-8500 2875);
DISPLAY INVISIBLE (-8500 2875);
FORCEPROP 1 LAST COMMENT_BODY TRUE
J 0
(-8125 2725);
DISPLAY 0.872340 (-8125 2725);
PAINT GREEN (-8125 2725);
DISPLAY INVISIBLE (-8125 2725);
FORCEPROP 1 LAST OFFPAGE TRUE
J 0
(-7925 2700);
DISPLAY 0.872340 (-7925 2700);
PAINT GREEN (-7925 2700);
DISPLAY INVISIBLE (-7925 2700);
FORCEPROP 2 LAST CDS_LIB mstr_standard
J 0
(-8250 2825);
DISPLAY 0.808511 (-8250 2825);
DISPLAY INVISIBLE (-8250 2825);
FORCEADD TAP..1
(-5950 3275);
FORCEPROP 3 LASTPIN (-6000 3275) SIG_NAME M_J_CPU0_SB_DQ<23>
J 0
(-5990 3285);
DISPLAY 0.659574 (-5990 3285);
PAINT MONO (-5990 3285);
DISPLAY INVISIBLE (-5990 3285);
FORCEPROP 1 LASTPIN (-6000 3275) BN 23
J 0
(-6012 3283);
DISPLAY 0.489362 (-6012 3283);
PAINT GREEN (-6012 3283);
FORCEPROP 2 LAST CDS_LIB mstr_standard
J 0
(-5950 3275);
DISPLAY 0.723404 (-5950 3275);
PAINT MONO (-5950 3275);
DISPLAY INVISIBLE (-5950 3275);
FORCEPROP 1 LAST BODY_TYPE PLUMBING
J 0
(-5950 3325);
DISPLAY 0.872340 (-5950 3325);
PAINT GREEN (-5950 3325);
DISPLAY INVISIBLE (-5950 3325);
FORCEPROP 1 LAST HDL_TAP TRUE
J 0
(-5625 3150);
DISPLAY 0.872340 (-5625 3150);
DISPLAY INVISIBLE (-5625 3150);
FORCEPROP 1 LAST PATH I60
J 0
(-5952 3275);
DISPLAY 0.872340 (-5952 3275);
PAINT GREEN (-5952 3275);
DISPLAY INVISIBLE (-5952 3275);
FORCEADD TAP..1
(-5950 3425);
FORCEPROP 3 LASTPIN (-6000 3425) SIG_NAME M_J_CPU0_SB_DQ<26>
J 0
(-5990 3435);
DISPLAY 0.659574 (-5990 3435);
PAINT MONO (-5990 3435);
DISPLAY INVISIBLE (-5990 3435);
FORCEPROP 1 LASTPIN (-6000 3425) BN 26
J 0
(-6012 3433);
DISPLAY 0.489362 (-6012 3433);
PAINT GREEN (-6012 3433);
FORCEPROP 2 LAST CDS_LIB mstr_standard
J 0
(-5950 3425);
DISPLAY 0.723404 (-5950 3425);
PAINT MONO (-5950 3425);
DISPLAY INVISIBLE (-5950 3425);
FORCEPROP 1 LAST BODY_TYPE PLUMBING
J 0
(-5950 3475);
DISPLAY 0.872340 (-5950 3475);
PAINT GREEN (-5950 3475);
DISPLAY INVISIBLE (-5950 3475);
FORCEPROP 1 LAST HDL_TAP TRUE
J 0
(-5625 3300);
DISPLAY 0.872340 (-5625 3300);
DISPLAY INVISIBLE (-5625 3300);
FORCEPROP 1 LAST PATH I61
J 0
(-5952 3425);
DISPLAY 0.872340 (-5952 3425);
PAINT GREEN (-5952 3425);
DISPLAY INVISIBLE (-5952 3425);
FORCEADD TAP..1
(-5950 3475);
FORCEPROP 3 LASTPIN (-6000 3475) SIG_NAME M_J_CPU0_SB_DQ<27>
J 0
(-5990 3485);
DISPLAY 0.659574 (-5990 3485);
PAINT MONO (-5990 3485);
DISPLAY INVISIBLE (-5990 3485);
FORCEPROP 1 LASTPIN (-6000 3475) BN 27
J 0
(-6012 3483);
DISPLAY 0.489362 (-6012 3483);
PAINT GREEN (-6012 3483);
FORCEPROP 2 LAST CDS_LIB mstr_standard
J 0
(-5950 3475);
DISPLAY 0.723404 (-5950 3475);
PAINT MONO (-5950 3475);
DISPLAY INVISIBLE (-5950 3475);
FORCEPROP 1 LAST BODY_TYPE PLUMBING
J 0
(-5950 3525);
DISPLAY 0.872340 (-5950 3525);
PAINT GREEN (-5950 3525);
DISPLAY INVISIBLE (-5950 3525);
FORCEPROP 1 LAST HDL_TAP TRUE
J 0
(-5625 3350);
DISPLAY 0.872340 (-5625 3350);
DISPLAY INVISIBLE (-5625 3350);
FORCEPROP 1 LAST PATH I62
J 0
(-5952 3475);
DISPLAY 0.872340 (-5952 3475);
PAINT GREEN (-5952 3475);
DISPLAY INVISIBLE (-5952 3475);
FORCEADD TAP..1
(-5950 3625);
FORCEPROP 3 LASTPIN (-6000 3625) SIG_NAME M_J_CPU0_SB_DQ<30>
J 0
(-5990 3635);
DISPLAY 0.659574 (-5990 3635);
PAINT MONO (-5990 3635);
DISPLAY INVISIBLE (-5990 3635);
FORCEPROP 1 LASTPIN (-6000 3625) BN 30
J 0
(-6012 3633);
DISPLAY 0.489362 (-6012 3633);
PAINT GREEN (-6012 3633);
FORCEPROP 2 LAST CDS_LIB mstr_standard
J 0
(-5950 3625);
DISPLAY 0.723404 (-5950 3625);
PAINT MONO (-5950 3625);
DISPLAY INVISIBLE (-5950 3625);
FORCEPROP 1 LAST BODY_TYPE PLUMBING
J 0
(-5950 3675);
DISPLAY 0.872340 (-5950 3675);
PAINT GREEN (-5950 3675);
DISPLAY INVISIBLE (-5950 3675);
FORCEPROP 1 LAST HDL_TAP TRUE
J 0
(-5625 3500);
DISPLAY 0.872340 (-5625 3500);
DISPLAY INVISIBLE (-5625 3500);
FORCEPROP 1 LAST PATH I63
J 0
(-5952 3625);
DISPLAY 0.872340 (-5952 3625);
PAINT GREEN (-5952 3625);
DISPLAY INVISIBLE (-5952 3625);
FORCEADD TAP..1
(-5950 3575);
FORCEPROP 3 LASTPIN (-6000 3575) SIG_NAME M_J_CPU0_SB_DQ<29>
J 0
(-5990 3585);
DISPLAY 0.659574 (-5990 3585);
PAINT MONO (-5990 3585);
DISPLAY INVISIBLE (-5990 3585);
FORCEPROP 1 LASTPIN (-6000 3575) BN 29
J 0
(-6012 3583);
DISPLAY 0.489362 (-6012 3583);
PAINT GREEN (-6012 3583);
FORCEPROP 2 LAST CDS_LIB mstr_standard
J 0
(-5950 3575);
DISPLAY 0.723404 (-5950 3575);
PAINT MONO (-5950 3575);
DISPLAY INVISIBLE (-5950 3575);
FORCEPROP 1 LAST BODY_TYPE PLUMBING
J 0
(-5950 3625);
DISPLAY 0.872340 (-5950 3625);
PAINT GREEN (-5950 3625);
DISPLAY INVISIBLE (-5950 3625);
FORCEPROP 1 LAST HDL_TAP TRUE
J 0
(-5625 3450);
DISPLAY 0.872340 (-5625 3450);
DISPLAY INVISIBLE (-5625 3450);
FORCEPROP 1 LAST PATH I64
J 0
(-5952 3575);
DISPLAY 0.872340 (-5952 3575);
PAINT GREEN (-5952 3575);
DISPLAY INVISIBLE (-5952 3575);
FORCEADD TAP..1
(-5950 3525);
FORCEPROP 3 LASTPIN (-6000 3525) SIG_NAME M_J_CPU0_SB_DQ<28>
J 0
(-5990 3535);
DISPLAY 0.659574 (-5990 3535);
PAINT MONO (-5990 3535);
DISPLAY INVISIBLE (-5990 3535);
FORCEPROP 1 LASTPIN (-6000 3525) BN 28
J 0
(-6012 3533);
DISPLAY 0.489362 (-6012 3533);
PAINT GREEN (-6012 3533);
FORCEPROP 2 LAST CDS_LIB mstr_standard
J 0
(-5950 3525);
DISPLAY 0.723404 (-5950 3525);
PAINT MONO (-5950 3525);
DISPLAY INVISIBLE (-5950 3525);
FORCEPROP 1 LAST BODY_TYPE PLUMBING
J 0
(-5950 3575);
DISPLAY 0.872340 (-5950 3575);
PAINT GREEN (-5950 3575);
DISPLAY INVISIBLE (-5950 3575);
FORCEPROP 1 LAST HDL_TAP TRUE
J 0
(-5625 3400);
DISPLAY 0.872340 (-5625 3400);
DISPLAY INVISIBLE (-5625 3400);
FORCEPROP 1 LAST PATH I65
J 0
(-5952 3525);
DISPLAY 0.872340 (-5952 3525);
PAINT GREEN (-5952 3525);
DISPLAY INVISIBLE (-5952 3525);
FORCEADD TAP..1
(-5950 3675);
FORCEPROP 3 LASTPIN (-6000 3675) SIG_NAME M_J_CPU0_SB_DQ<31>
J 0
(-5990 3685);
DISPLAY 0.659574 (-5990 3685);
PAINT MONO (-5990 3685);
DISPLAY INVISIBLE (-5990 3685);
FORCEPROP 1 LASTPIN (-6000 3675) BN 31
J 0
(-6012 3683);
DISPLAY 0.489362 (-6012 3683);
PAINT GREEN (-6012 3683);
FORCEPROP 2 LAST CDS_LIB mstr_standard
J 0
(-5950 3675);
DISPLAY 0.723404 (-5950 3675);
PAINT MONO (-5950 3675);
DISPLAY INVISIBLE (-5950 3675);
FORCEPROP 1 LAST BODY_TYPE PLUMBING
J 0
(-5950 3725);
DISPLAY 0.872340 (-5950 3725);
PAINT GREEN (-5950 3725);
DISPLAY INVISIBLE (-5950 3725);
FORCEPROP 1 LAST HDL_TAP TRUE
J 0
(-5625 3550);
DISPLAY 0.872340 (-5625 3550);
DISPLAY INVISIBLE (-5625 3550);
FORCEPROP 1 LAST PATH I66
J 0
(-5952 3675);
DISPLAY 0.872340 (-5952 3675);
PAINT GREEN (-5952 3675);
DISPLAY INVISIBLE (-5952 3675);
FORCEADD OFFPAGE..5
(-8050 2975);
FORCEPROP 2 LAST $XR0 19 
J 0
(-8304 2975);
DISPLAY 0.638298 (-8304 2975);
PAINT MONO (-8304 2975);
FORCEPROP 2 LAST PATH I7
J 0
(-8000 3050);
DISPLAY 1.021277 (-8000 3050);
DISPLAY INVISIBLE (-8000 3050);
FORCEPROP 1 LAST COMMENT_BODY TRUE
J 0
(-7950 2900);
DISPLAY 0.872340 (-7950 2900);
PAINT GREEN (-7950 2900);
DISPLAY INVISIBLE (-7950 2900);
FORCEPROP 1 LAST OFFPAGE TRUE
J 0
(-7725 2850);
DISPLAY 0.872340 (-7725 2850);
PAINT GREEN (-7725 2850);
DISPLAY INVISIBLE (-7725 2850);
FORCEPROP 2 LAST CDS_LIB mstr_standard
J 0
(-8050 2975);
DISPLAY INVISIBLE (-8050 2975);
FORCEADD OFFPAGE..3
(-5200 3725);
FORCEPROP 2 LAST $XR0 19 
J 0
(-4896 3725);
DISPLAY 0.638298 (-4896 3725);
PAINT MONO (-4896 3725);
FORCEPROP 2 LAST PATH I74
J 0
(-5000 3800);
DISPLAY 1.021277 (-5000 3800);
DISPLAY INVISIBLE (-5000 3800);
FORCEPROP 1 LAST COMMENT_BODY TRUE
J 0
(-5250 3625);
DISPLAY 0.872340 (-5250 3625);
PAINT GREEN (-5250 3625);
DISPLAY INVISIBLE (-5250 3625);
FORCEPROP 1 LAST OFFPAGE TRUE
J 0
(-4875 3600);
DISPLAY 0.872340 (-4875 3600);
PAINT GREEN (-4875 3600);
DISPLAY INVISIBLE (-4875 3600);
FORCEPROP 2 LAST CDS_LIB mstr_standard
J 0
(-5200 3725);
DISPLAY 0.723404 (-5200 3725);
PAINT MONO (-5200 3725);
DISPLAY INVISIBLE (-5200 3725);
FORCEADD TAP..1
R 2
(-7650 3775);
FORCEPROP 3 LASTPIN (-7600 3775) SIG_NAME M_J_CPU0_SA_CB<4>
J 0
(-7590 3785);
DISPLAY 0.659574 (-7590 3785);
PAINT MONO (-7590 3785);
DISPLAY INVISIBLE (-7590 3785);
FORCEPROP 1 LASTPIN (-7600 3775) BN 4
J 2
(-7588 3783);
DISPLAY 0.489362 (-7588 3783);
PAINT GREEN (-7588 3783);
FORCEPROP 2 LAST CDS_LIB mstr_standard
J 0
(-7650 3775);
DISPLAY 0.723404 (-7650 3775);
PAINT MONO (-7650 3775);
DISPLAY INVISIBLE (-7650 3775);
FORCEPROP 1 LAST BODY_TYPE PLUMBING
J 2
(-7650 3825);
DISPLAY 0.872340 (-7650 3825);
PAINT GREEN (-7650 3825);
DISPLAY INVISIBLE (-7650 3825);
FORCEPROP 1 LAST HDL_TAP TRUE
J 2
(-7975 3650);
DISPLAY 0.872340 (-7975 3650);
DISPLAY INVISIBLE (-7975 3650);
FORCEPROP 1 LAST PATH I76
J 2
(-7648 3775);
DISPLAY 0.872340 (-7648 3775);
PAINT GREEN (-7648 3775);
DISPLAY INVISIBLE (-7648 3775);
FORCEADD TAP..1
R 2
(-7650 3825);
FORCEPROP 3 LASTPIN (-7600 3825) SIG_NAME M_J_CPU0_SA_CB<5>
J 0
(-7590 3835);
DISPLAY 0.659574 (-7590 3835);
PAINT MONO (-7590 3835);
DISPLAY INVISIBLE (-7590 3835);
FORCEPROP 1 LASTPIN (-7600 3825) BN 5
J 2
(-7588 3833);
DISPLAY 0.489362 (-7588 3833);
PAINT GREEN (-7588 3833);
FORCEPROP 2 LAST CDS_LIB mstr_standard
J 0
(-7650 3825);
DISPLAY 0.723404 (-7650 3825);
PAINT MONO (-7650 3825);
DISPLAY INVISIBLE (-7650 3825);
FORCEPROP 1 LAST BODY_TYPE PLUMBING
J 2
(-7650 3875);
DISPLAY 0.872340 (-7650 3875);
PAINT GREEN (-7650 3875);
DISPLAY INVISIBLE (-7650 3875);
FORCEPROP 1 LAST HDL_TAP TRUE
J 2
(-7975 3700);
DISPLAY 0.872340 (-7975 3700);
DISPLAY INVISIBLE (-7975 3700);
FORCEPROP 1 LAST PATH I77
J 2
(-7648 3825);
DISPLAY 0.872340 (-7648 3825);
PAINT GREEN (-7648 3825);
DISPLAY INVISIBLE (-7648 3825);
FORCEADD TAP..1
R 2
(-7650 3875);
FORCEPROP 3 LASTPIN (-7600 3875) SIG_NAME M_J_CPU0_SA_CB<6>
J 0
(-7590 3885);
DISPLAY 0.659574 (-7590 3885);
PAINT MONO (-7590 3885);
DISPLAY INVISIBLE (-7590 3885);
FORCEPROP 1 LASTPIN (-7600 3875) BN 6
J 2
(-7588 3883);
DISPLAY 0.489362 (-7588 3883);
PAINT GREEN (-7588 3883);
FORCEPROP 2 LAST CDS_LIB mstr_standard
J 0
(-7650 3875);
DISPLAY 0.723404 (-7650 3875);
PAINT MONO (-7650 3875);
DISPLAY INVISIBLE (-7650 3875);
FORCEPROP 1 LAST BODY_TYPE PLUMBING
J 2
(-7650 3925);
DISPLAY 0.872340 (-7650 3925);
PAINT GREEN (-7650 3925);
DISPLAY INVISIBLE (-7650 3925);
FORCEPROP 1 LAST HDL_TAP TRUE
J 2
(-7975 3750);
DISPLAY 0.872340 (-7975 3750);
DISPLAY INVISIBLE (-7975 3750);
FORCEPROP 1 LAST PATH I78
J 2
(-7648 3875);
DISPLAY 0.872340 (-7648 3875);
PAINT GREEN (-7648 3875);
DISPLAY INVISIBLE (-7648 3875);
FORCEADD TAP..1
R 2
(-7650 3925);
FORCEPROP 3 LASTPIN (-7600 3925) SIG_NAME M_J_CPU0_SA_CB<7>
J 0
(-7590 3935);
DISPLAY 0.659574 (-7590 3935);
PAINT MONO (-7590 3935);
DISPLAY INVISIBLE (-7590 3935);
FORCEPROP 1 LASTPIN (-7600 3925) BN 7
J 2
(-7588 3933);
DISPLAY 0.489362 (-7588 3933);
PAINT GREEN (-7588 3933);
FORCEPROP 2 LAST CDS_LIB mstr_standard
J 0
(-7650 3925);
DISPLAY 0.723404 (-7650 3925);
PAINT MONO (-7650 3925);
DISPLAY INVISIBLE (-7650 3925);
FORCEPROP 1 LAST BODY_TYPE PLUMBING
J 2
(-7650 3975);
DISPLAY 0.872340 (-7650 3975);
PAINT GREEN (-7650 3975);
DISPLAY INVISIBLE (-7650 3975);
FORCEPROP 1 LAST HDL_TAP TRUE
J 2
(-7975 3800);
DISPLAY 0.872340 (-7975 3800);
DISPLAY INVISIBLE (-7975 3800);
FORCEPROP 1 LAST PATH I79
J 2
(-7648 3925);
DISPLAY 0.872340 (-7648 3925);
PAINT GREEN (-7648 3925);
DISPLAY INVISIBLE (-7648 3925);
FORCEADD OFFPAGE..1
(-8050 3025);
FORCEPROP 2 LAST $XR0 19 
J 0
(-8301 3025);
DISPLAY 0.638298 (-8301 3025);
PAINT MONO (-8301 3025);
FORCEPROP 2 LAST PATH I8
J 0
(-8475 3075);
DISPLAY 1.021277 (-8475 3075);
DISPLAY INVISIBLE (-8475 3075);
FORCEPROP 1 LAST COMMENT_BODY TRUE
J 0
(-7925 2925);
DISPLAY 0.872340 (-7925 2925);
PAINT GREEN (-7925 2925);
DISPLAY INVISIBLE (-7925 2925);
FORCEPROP 1 LAST OFFPAGE TRUE
J 0
(-7725 2900);
DISPLAY 0.872340 (-7725 2900);
PAINT GREEN (-7725 2900);
DISPLAY INVISIBLE (-7725 2900);
FORCEPROP 2 LAST CDS_LIB mstr_standard
J 0
(-8050 3025);
DISPLAY 0.808511 (-8050 3025);
DISPLAY INVISIBLE (-8050 3025);
FORCEADD TAP..1
R 2
(-7650 4625);
FORCEPROP 3 LASTPIN (-7600 4625) SIG_NAME M_J_CPU0_SB_CA<0>
J 0
(-7590 4635);
DISPLAY 0.659574 (-7590 4635);
PAINT MONO (-7590 4635);
DISPLAY INVISIBLE (-7590 4635);
FORCEPROP 1 LASTPIN (-7600 4625) BN 0
J 2
(-7588 4633);
DISPLAY 0.489362 (-7588 4633);
PAINT GREEN (-7588 4633);
FORCEPROP 2 LAST CDS_LIB mstr_standard
J 0
(-7650 4625);
DISPLAY 0.723404 (-7650 4625);
PAINT MONO (-7650 4625);
DISPLAY INVISIBLE (-7650 4625);
FORCEPROP 1 LAST BODY_TYPE PLUMBING
J 2
(-7650 4675);
DISPLAY 0.872340 (-7650 4675);
PAINT GREEN (-7650 4675);
DISPLAY INVISIBLE (-7650 4675);
FORCEPROP 1 LAST HDL_TAP TRUE
J 2
(-7975 4500);
DISPLAY 0.872340 (-7975 4500);
DISPLAY INVISIBLE (-7975 4500);
FORCEPROP 1 LAST PATH I80
J 2
(-7648 4625);
DISPLAY 0.872340 (-7648 4625);
PAINT GREEN (-7648 4625);
DISPLAY INVISIBLE (-7648 4625);
FORCEADD TAP..1
R 2
(-7650 4675);
FORCEPROP 3 LASTPIN (-7600 4675) SIG_NAME M_J_CPU0_SB_CA<1>
J 0
(-7590 4685);
DISPLAY 0.659574 (-7590 4685);
PAINT MONO (-7590 4685);
DISPLAY INVISIBLE (-7590 4685);
FORCEPROP 1 LASTPIN (-7600 4675) BN 1
J 2
(-7588 4683);
DISPLAY 0.489362 (-7588 4683);
PAINT GREEN (-7588 4683);
FORCEPROP 2 LAST CDS_LIB mstr_standard
J 0
(-7650 4675);
DISPLAY 0.723404 (-7650 4675);
PAINT MONO (-7650 4675);
DISPLAY INVISIBLE (-7650 4675);
FORCEPROP 1 LAST BODY_TYPE PLUMBING
J 2
(-7650 4725);
DISPLAY 0.872340 (-7650 4725);
PAINT GREEN (-7650 4725);
DISPLAY INVISIBLE (-7650 4725);
FORCEPROP 1 LAST HDL_TAP TRUE
J 2
(-7975 4550);
DISPLAY 0.872340 (-7975 4550);
DISPLAY INVISIBLE (-7975 4550);
FORCEPROP 1 LAST PATH I81
J 2
(-7648 4675);
DISPLAY 0.872340 (-7648 4675);
PAINT GREEN (-7648 4675);
DISPLAY INVISIBLE (-7648 4675);
FORCEADD TAP..1
R 2
(-7650 4725);
FORCEPROP 3 LASTPIN (-7600 4725) SIG_NAME M_J_CPU0_SB_CA<2>
J 0
(-7590 4735);
DISPLAY 0.659574 (-7590 4735);
PAINT MONO (-7590 4735);
DISPLAY INVISIBLE (-7590 4735);
FORCEPROP 1 LASTPIN (-7600 4725) BN 2
J 2
(-7588 4733);
DISPLAY 0.489362 (-7588 4733);
PAINT GREEN (-7588 4733);
FORCEPROP 2 LAST CDS_LIB mstr_standard
J 0
(-7650 4725);
DISPLAY 0.723404 (-7650 4725);
PAINT MONO (-7650 4725);
DISPLAY INVISIBLE (-7650 4725);
FORCEPROP 1 LAST BODY_TYPE PLUMBING
J 2
(-7650 4775);
DISPLAY 0.872340 (-7650 4775);
PAINT GREEN (-7650 4775);
DISPLAY INVISIBLE (-7650 4775);
FORCEPROP 1 LAST HDL_TAP TRUE
J 2
(-7975 4600);
DISPLAY 0.872340 (-7975 4600);
DISPLAY INVISIBLE (-7975 4600);
FORCEPROP 1 LAST PATH I82
J 2
(-7648 4725);
DISPLAY 0.872340 (-7648 4725);
PAINT GREEN (-7648 4725);
DISPLAY INVISIBLE (-7648 4725);
FORCEADD TAP..1
R 2
(-7650 4775);
FORCEPROP 3 LASTPIN (-7600 4775) SIG_NAME M_J_CPU0_SB_CA<3>
J 0
(-7590 4785);
DISPLAY 0.659574 (-7590 4785);
PAINT MONO (-7590 4785);
DISPLAY INVISIBLE (-7590 4785);
FORCEPROP 1 LASTPIN (-7600 4775) BN 3
J 2
(-7588 4783);
DISPLAY 0.489362 (-7588 4783);
PAINT GREEN (-7588 4783);
FORCEPROP 2 LAST CDS_LIB mstr_standard
J 0
(-7650 4775);
DISPLAY 0.723404 (-7650 4775);
PAINT MONO (-7650 4775);
DISPLAY INVISIBLE (-7650 4775);
FORCEPROP 1 LAST BODY_TYPE PLUMBING
J 2
(-7650 4825);
DISPLAY 0.872340 (-7650 4825);
PAINT GREEN (-7650 4825);
DISPLAY INVISIBLE (-7650 4825);
FORCEPROP 1 LAST HDL_TAP TRUE
J 2
(-7975 4650);
DISPLAY 0.872340 (-7975 4650);
DISPLAY INVISIBLE (-7975 4650);
FORCEPROP 1 LAST PATH I83
J 2
(-7648 4775);
DISPLAY 0.872340 (-7648 4775);
PAINT GREEN (-7648 4775);
DISPLAY INVISIBLE (-7648 4775);
FORCEADD TAP..1
R 2
(-7650 4825);
FORCEPROP 3 LASTPIN (-7600 4825) SIG_NAME M_J_CPU0_SB_CA<4>
J 0
(-7590 4835);
DISPLAY 0.659574 (-7590 4835);
PAINT MONO (-7590 4835);
DISPLAY INVISIBLE (-7590 4835);
FORCEPROP 1 LASTPIN (-7600 4825) BN 4
J 2
(-7588 4833);
DISPLAY 0.489362 (-7588 4833);
PAINT GREEN (-7588 4833);
FORCEPROP 2 LAST CDS_LIB mstr_standard
J 0
(-7650 4825);
DISPLAY 0.723404 (-7650 4825);
PAINT MONO (-7650 4825);
DISPLAY INVISIBLE (-7650 4825);
FORCEPROP 1 LAST BODY_TYPE PLUMBING
J 2
(-7650 4875);
DISPLAY 0.872340 (-7650 4875);
PAINT GREEN (-7650 4875);
DISPLAY INVISIBLE (-7650 4875);
FORCEPROP 1 LAST HDL_TAP TRUE
J 2
(-7975 4700);
DISPLAY 0.872340 (-7975 4700);
DISPLAY INVISIBLE (-7975 4700);
FORCEPROP 1 LAST PATH I84
J 2
(-7648 4825);
DISPLAY 0.872340 (-7648 4825);
PAINT GREEN (-7648 4825);
DISPLAY INVISIBLE (-7648 4825);
FORCEADD TAP..1
R 2
(-7650 4875);
FORCEPROP 3 LASTPIN (-7600 4875) SIG_NAME M_J_CPU0_SB_CA<5>
J 0
(-7590 4885);
DISPLAY 0.659574 (-7590 4885);
PAINT MONO (-7590 4885);
DISPLAY INVISIBLE (-7590 4885);
FORCEPROP 1 LASTPIN (-7600 4875) BN 5
J 2
(-7588 4883);
DISPLAY 0.489362 (-7588 4883);
PAINT GREEN (-7588 4883);
FORCEPROP 2 LAST CDS_LIB mstr_standard
J 0
(-7650 4875);
DISPLAY 0.723404 (-7650 4875);
PAINT MONO (-7650 4875);
DISPLAY INVISIBLE (-7650 4875);
FORCEPROP 1 LAST BODY_TYPE PLUMBING
J 2
(-7650 4925);
DISPLAY 0.872340 (-7650 4925);
PAINT GREEN (-7650 4925);
DISPLAY INVISIBLE (-7650 4925);
FORCEPROP 1 LAST HDL_TAP TRUE
J 2
(-7975 4750);
DISPLAY 0.872340 (-7975 4750);
DISPLAY INVISIBLE (-7975 4750);
FORCEPROP 1 LAST PATH I85
J 2
(-7648 4875);
DISPLAY 0.872340 (-7648 4875);
PAINT GREEN (-7648 4875);
DISPLAY INVISIBLE (-7648 4875);
FORCEADD TAP..1
R 2
(-7650 4925);
FORCEPROP 3 LASTPIN (-7600 4925) SIG_NAME M_J_CPU0_SB_CA<6>
J 0
(-7590 4935);
DISPLAY 0.659574 (-7590 4935);
PAINT MONO (-7590 4935);
DISPLAY INVISIBLE (-7590 4935);
FORCEPROP 1 LASTPIN (-7600 4925) BN 6
J 2
(-7588 4933);
DISPLAY 0.489362 (-7588 4933);
PAINT GREEN (-7588 4933);
FORCEPROP 2 LAST CDS_LIB mstr_standard
J 0
(-7650 4925);
DISPLAY 0.723404 (-7650 4925);
PAINT MONO (-7650 4925);
DISPLAY INVISIBLE (-7650 4925);
FORCEPROP 1 LAST BODY_TYPE PLUMBING
J 2
(-7650 4975);
DISPLAY 0.872340 (-7650 4975);
PAINT GREEN (-7650 4975);
DISPLAY INVISIBLE (-7650 4975);
FORCEPROP 1 LAST HDL_TAP TRUE
J 2
(-7975 4800);
DISPLAY 0.872340 (-7975 4800);
DISPLAY INVISIBLE (-7975 4800);
FORCEPROP 1 LAST PATH I86
J 2
(-7648 4925);
DISPLAY 0.872340 (-7648 4925);
PAINT GREEN (-7648 4925);
DISPLAY INVISIBLE (-7648 4925);
FORCEADD TAP..1
R 2
(-7650 5025);
FORCEPROP 3 LASTPIN (-7600 5025) SIG_NAME M_J_CPU0_SA_CA<0>
J 0
(-7590 5035);
DISPLAY 0.659574 (-7590 5035);
PAINT MONO (-7590 5035);
DISPLAY INVISIBLE (-7590 5035);
FORCEPROP 1 LASTPIN (-7600 5025) BN 0
J 2
(-7588 5033);
DISPLAY 0.489362 (-7588 5033);
PAINT GREEN (-7588 5033);
FORCEPROP 2 LAST CDS_LIB mstr_standard
J 0
(-7650 5025);
DISPLAY 0.723404 (-7650 5025);
PAINT MONO (-7650 5025);
DISPLAY INVISIBLE (-7650 5025);
FORCEPROP 1 LAST BODY_TYPE PLUMBING
J 2
(-7650 5075);
DISPLAY 0.872340 (-7650 5075);
PAINT GREEN (-7650 5075);
DISPLAY INVISIBLE (-7650 5075);
FORCEPROP 1 LAST HDL_TAP TRUE
J 2
(-7975 4900);
DISPLAY 0.872340 (-7975 4900);
DISPLAY INVISIBLE (-7975 4900);
FORCEPROP 1 LAST PATH I87
J 2
(-7648 5025);
DISPLAY 0.872340 (-7648 5025);
PAINT GREEN (-7648 5025);
DISPLAY INVISIBLE (-7648 5025);
FORCEADD TAP..1
R 2
(-7650 5075);
FORCEPROP 3 LASTPIN (-7600 5075) SIG_NAME M_J_CPU0_SA_CA<1>
J 0
(-7590 5085);
DISPLAY 0.659574 (-7590 5085);
PAINT MONO (-7590 5085);
DISPLAY INVISIBLE (-7590 5085);
FORCEPROP 1 LASTPIN (-7600 5075) BN 1
J 2
(-7588 5083);
DISPLAY 0.489362 (-7588 5083);
PAINT GREEN (-7588 5083);
FORCEPROP 2 LAST CDS_LIB mstr_standard
J 0
(-7650 5075);
DISPLAY 0.723404 (-7650 5075);
PAINT MONO (-7650 5075);
DISPLAY INVISIBLE (-7650 5075);
FORCEPROP 1 LAST BODY_TYPE PLUMBING
J 2
(-7650 5125);
DISPLAY 0.872340 (-7650 5125);
PAINT GREEN (-7650 5125);
DISPLAY INVISIBLE (-7650 5125);
FORCEPROP 1 LAST HDL_TAP TRUE
J 2
(-7975 4950);
DISPLAY 0.872340 (-7975 4950);
DISPLAY INVISIBLE (-7975 4950);
FORCEPROP 1 LAST PATH I88
J 2
(-7648 5075);
DISPLAY 0.872340 (-7648 5075);
PAINT GREEN (-7648 5075);
DISPLAY INVISIBLE (-7648 5075);
FORCEADD TAP..1
R 2
(-7650 5125);
FORCEPROP 3 LASTPIN (-7600 5125) SIG_NAME M_J_CPU0_SA_CA<2>
J 0
(-7590 5135);
DISPLAY 0.659574 (-7590 5135);
PAINT MONO (-7590 5135);
DISPLAY INVISIBLE (-7590 5135);
FORCEPROP 1 LASTPIN (-7600 5125) BN 2
J 2
(-7588 5133);
DISPLAY 0.489362 (-7588 5133);
PAINT GREEN (-7588 5133);
FORCEPROP 2 LAST CDS_LIB mstr_standard
J 0
(-7650 5125);
DISPLAY 0.723404 (-7650 5125);
PAINT MONO (-7650 5125);
DISPLAY INVISIBLE (-7650 5125);
FORCEPROP 1 LAST BODY_TYPE PLUMBING
J 2
(-7650 5175);
DISPLAY 0.872340 (-7650 5175);
PAINT GREEN (-7650 5175);
DISPLAY INVISIBLE (-7650 5175);
FORCEPROP 1 LAST HDL_TAP TRUE
J 2
(-7975 5000);
DISPLAY 0.872340 (-7975 5000);
DISPLAY INVISIBLE (-7975 5000);
FORCEPROP 1 LAST PATH I89
J 2
(-7648 5125);
DISPLAY 0.872340 (-7648 5125);
PAINT GREEN (-7648 5125);
DISPLAY INVISIBLE (-7648 5125);
FORCEADD VCC_CORE..1
(-8450 3375);
FORCEPROP 3 LASTPIN (-8450 3325) SIG_NAME P3V3_STBY\g
J 0
(-8440 3335);
DISPLAY 0.659574 (-8440 3335);
PAINT MONO (-8440 3335);
DISPLAY INVISIBLE (-8440 3335);
FORCEPROP 1 LAST HDL_POWER P3V3_STBY
J 1
(-8450 3425);
DISPLAY 0.489362 (-8450 3425);
PAINT GREEN (-8450 3425);
FORCEPROP 2 LAST CDS_LIB mstr_symbols
J 0
(-8450 3375);
PAINT MONO (-8450 3375);
DISPLAY INVISIBLE (-8450 3375);
FORCEPROP 1 LAST PATH I9
J 0
(-8400 3400);
DISPLAY 0.872340 (-8400 3400);
PAINT AQUA (-8400 3400);
DISPLAY INVISIBLE (-8400 3400);
FORCEPROP 0 LAST VOLTAGE 3.3
J 0
(-8725 3525);
DISPLAY 1.021277 (-8725 3525);
PAINT SKYBLUE (-8725 3525);
DISPLAY INVISIBLE (-8725 3525);
FORCEPROP 2 LAST ROOM PVCCINFAON_CPU0_CTRL
J 0
(-8450 3475);
DISPLAY 0.808511 (-8450 3475);
PAINT RED (-8450 3475);
DISPLAY INVISIBLE (-8450 3475);
FORCEADD TAP..1
R 2
(-7650 5175);
FORCEPROP 3 LASTPIN (-7600 5175) SIG_NAME M_J_CPU0_SA_CA<3>
J 0
(-7590 5185);
DISPLAY 0.659574 (-7590 5185);
PAINT MONO (-7590 5185);
DISPLAY INVISIBLE (-7590 5185);
FORCEPROP 1 LASTPIN (-7600 5175) BN 3
J 2
(-7588 5183);
DISPLAY 0.489362 (-7588 5183);
PAINT GREEN (-7588 5183);
FORCEPROP 2 LAST CDS_LIB mstr_standard
J 0
(-7650 5175);
DISPLAY 0.723404 (-7650 5175);
PAINT MONO (-7650 5175);
DISPLAY INVISIBLE (-7650 5175);
FORCEPROP 1 LAST BODY_TYPE PLUMBING
J 2
(-7650 5225);
DISPLAY 0.872340 (-7650 5225);
PAINT GREEN (-7650 5225);
DISPLAY INVISIBLE (-7650 5225);
FORCEPROP 1 LAST HDL_TAP TRUE
J 2
(-7975 5050);
DISPLAY 0.872340 (-7975 5050);
DISPLAY INVISIBLE (-7975 5050);
FORCEPROP 1 LAST PATH I90
J 2
(-7648 5175);
DISPLAY 0.872340 (-7648 5175);
PAINT GREEN (-7648 5175);
DISPLAY INVISIBLE (-7648 5175);
FORCEADD TAP..1
R 2
(-7650 5225);
FORCEPROP 3 LASTPIN (-7600 5225) SIG_NAME M_J_CPU0_SA_CA<4>
J 0
(-7590 5235);
DISPLAY 0.659574 (-7590 5235);
PAINT MONO (-7590 5235);
DISPLAY INVISIBLE (-7590 5235);
FORCEPROP 1 LASTPIN (-7600 5225) BN 4
J 2
(-7588 5233);
DISPLAY 0.489362 (-7588 5233);
PAINT GREEN (-7588 5233);
FORCEPROP 2 LAST CDS_LIB mstr_standard
J 0
(-7650 5225);
DISPLAY 0.723404 (-7650 5225);
PAINT MONO (-7650 5225);
DISPLAY INVISIBLE (-7650 5225);
FORCEPROP 1 LAST BODY_TYPE PLUMBING
J 2
(-7650 5275);
DISPLAY 0.872340 (-7650 5275);
PAINT GREEN (-7650 5275);
DISPLAY INVISIBLE (-7650 5275);
FORCEPROP 1 LAST HDL_TAP TRUE
J 2
(-7975 5100);
DISPLAY 0.872340 (-7975 5100);
DISPLAY INVISIBLE (-7975 5100);
FORCEPROP 1 LAST PATH I91
J 2
(-7648 5225);
DISPLAY 0.872340 (-7648 5225);
PAINT GREEN (-7648 5225);
DISPLAY INVISIBLE (-7648 5225);
FORCEADD TAP..1
R 2
(-7650 5275);
FORCEPROP 3 LASTPIN (-7600 5275) SIG_NAME M_J_CPU0_SA_CA<5>
J 0
(-7590 5285);
DISPLAY 0.659574 (-7590 5285);
PAINT MONO (-7590 5285);
DISPLAY INVISIBLE (-7590 5285);
FORCEPROP 1 LASTPIN (-7600 5275) BN 5
J 2
(-7588 5283);
DISPLAY 0.489362 (-7588 5283);
PAINT GREEN (-7588 5283);
FORCEPROP 2 LAST CDS_LIB mstr_standard
J 0
(-7650 5275);
DISPLAY 0.723404 (-7650 5275);
PAINT MONO (-7650 5275);
DISPLAY INVISIBLE (-7650 5275);
FORCEPROP 1 LAST BODY_TYPE PLUMBING
J 2
(-7650 5325);
DISPLAY 0.872340 (-7650 5325);
PAINT GREEN (-7650 5325);
DISPLAY INVISIBLE (-7650 5325);
FORCEPROP 1 LAST HDL_TAP TRUE
J 2
(-7975 5150);
DISPLAY 0.872340 (-7975 5150);
DISPLAY INVISIBLE (-7975 5150);
FORCEPROP 1 LAST PATH I92
J 2
(-7648 5275);
DISPLAY 0.872340 (-7648 5275);
PAINT GREEN (-7648 5275);
DISPLAY INVISIBLE (-7648 5275);
FORCEADD TAP..1
R 2
(-7650 5325);
FORCEPROP 3 LASTPIN (-7600 5325) SIG_NAME M_J_CPU0_SA_CA<6>
J 0
(-7590 5335);
DISPLAY 0.659574 (-7590 5335);
PAINT MONO (-7590 5335);
DISPLAY INVISIBLE (-7590 5335);
FORCEPROP 1 LASTPIN (-7600 5325) BN 6
J 2
(-7588 5333);
DISPLAY 0.489362 (-7588 5333);
PAINT GREEN (-7588 5333);
FORCEPROP 2 LAST CDS_LIB mstr_standard
J 0
(-7650 5325);
DISPLAY 0.723404 (-7650 5325);
PAINT MONO (-7650 5325);
DISPLAY INVISIBLE (-7650 5325);
FORCEPROP 1 LAST BODY_TYPE PLUMBING
J 2
(-7650 5375);
DISPLAY 0.872340 (-7650 5375);
PAINT GREEN (-7650 5375);
DISPLAY INVISIBLE (-7650 5375);
FORCEPROP 1 LAST HDL_TAP TRUE
J 2
(-7975 5200);
DISPLAY 0.872340 (-7975 5200);
DISPLAY INVISIBLE (-7975 5200);
FORCEPROP 1 LAST PATH I93
J 2
(-7648 5325);
DISPLAY 0.872340 (-7648 5325);
PAINT GREEN (-7648 5325);
DISPLAY INVISIBLE (-7648 5325);
FORCEADD TAP..1
(-5950 3775);
FORCEPROP 3 LASTPIN (-6000 3775) SIG_NAME M_J_CPU0_SA_DQ<0>
J 0
(-5990 3785);
DISPLAY 0.659574 (-5990 3785);
PAINT MONO (-5990 3785);
DISPLAY INVISIBLE (-5990 3785);
FORCEPROP 1 LASTPIN (-6000 3775) BN 0
J 0
(-6012 3783);
DISPLAY 0.489362 (-6012 3783);
PAINT GREEN (-6012 3783);
FORCEPROP 2 LAST CDS_LIB mstr_standard
J 0
(-5950 3775);
DISPLAY 0.723404 (-5950 3775);
PAINT MONO (-5950 3775);
DISPLAY INVISIBLE (-5950 3775);
FORCEPROP 1 LAST BODY_TYPE PLUMBING
J 0
(-5950 3825);
DISPLAY 0.872340 (-5950 3825);
PAINT GREEN (-5950 3825);
DISPLAY INVISIBLE (-5950 3825);
FORCEPROP 1 LAST HDL_TAP TRUE
J 0
(-5625 3650);
DISPLAY 0.872340 (-5625 3650);
DISPLAY INVISIBLE (-5625 3650);
FORCEPROP 1 LAST PATH I94
J 0
(-5952 3775);
DISPLAY 0.872340 (-5952 3775);
PAINT GREEN (-5952 3775);
DISPLAY INVISIBLE (-5952 3775);
FORCEADD TAP..1
(-5950 3875);
FORCEPROP 3 LASTPIN (-6000 3875) SIG_NAME M_J_CPU0_SA_DQ<2>
J 0
(-5990 3885);
DISPLAY 0.659574 (-5990 3885);
PAINT MONO (-5990 3885);
DISPLAY INVISIBLE (-5990 3885);
FORCEPROP 1 LASTPIN (-6000 3875) BN 2
J 0
(-6012 3883);
DISPLAY 0.489362 (-6012 3883);
PAINT GREEN (-6012 3883);
FORCEPROP 2 LAST CDS_LIB mstr_standard
J 0
(-5950 3875);
DISPLAY 0.723404 (-5950 3875);
PAINT MONO (-5950 3875);
DISPLAY INVISIBLE (-5950 3875);
FORCEPROP 1 LAST BODY_TYPE PLUMBING
J 0
(-5950 3925);
DISPLAY 0.872340 (-5950 3925);
PAINT GREEN (-5950 3925);
DISPLAY INVISIBLE (-5950 3925);
FORCEPROP 1 LAST HDL_TAP TRUE
J 0
(-5625 3750);
DISPLAY 0.872340 (-5625 3750);
DISPLAY INVISIBLE (-5625 3750);
FORCEPROP 1 LAST PATH I95
J 0
(-5952 3875);
DISPLAY 0.872340 (-5952 3875);
PAINT GREEN (-5952 3875);
DISPLAY INVISIBLE (-5952 3875);
FORCEADD TAP..1
(-5950 3825);
FORCEPROP 3 LASTPIN (-6000 3825) SIG_NAME M_J_CPU0_SA_DQ<1>
J 0
(-5990 3835);
DISPLAY 0.659574 (-5990 3835);
PAINT MONO (-5990 3835);
DISPLAY INVISIBLE (-5990 3835);
FORCEPROP 1 LASTPIN (-6000 3825) BN 1
J 0
(-6012 3833);
DISPLAY 0.489362 (-6012 3833);
PAINT GREEN (-6012 3833);
FORCEPROP 2 LAST CDS_LIB mstr_standard
J 0
(-5950 3825);
DISPLAY 0.723404 (-5950 3825);
PAINT MONO (-5950 3825);
DISPLAY INVISIBLE (-5950 3825);
FORCEPROP 1 LAST BODY_TYPE PLUMBING
J 0
(-5950 3875);
DISPLAY 0.872340 (-5950 3875);
PAINT GREEN (-5950 3875);
DISPLAY INVISIBLE (-5950 3875);
FORCEPROP 1 LAST HDL_TAP TRUE
J 0
(-5625 3700);
DISPLAY 0.872340 (-5625 3700);
DISPLAY INVISIBLE (-5625 3700);
FORCEPROP 1 LAST PATH I96
J 0
(-5952 3825);
DISPLAY 0.872340 (-5952 3825);
PAINT GREEN (-5952 3825);
DISPLAY INVISIBLE (-5952 3825);
FORCEADD TAP..1
(-5950 3925);
FORCEPROP 3 LASTPIN (-6000 3925) SIG_NAME M_J_CPU0_SA_DQ<3>
J 0
(-5990 3935);
DISPLAY 0.659574 (-5990 3935);
PAINT MONO (-5990 3935);
DISPLAY INVISIBLE (-5990 3935);
FORCEPROP 1 LASTPIN (-6000 3925) BN 3
J 0
(-6012 3933);
DISPLAY 0.489362 (-6012 3933);
PAINT GREEN (-6012 3933);
FORCEPROP 2 LAST CDS_LIB mstr_standard
J 0
(-5950 3925);
DISPLAY 0.723404 (-5950 3925);
PAINT MONO (-5950 3925);
DISPLAY INVISIBLE (-5950 3925);
FORCEPROP 1 LAST BODY_TYPE PLUMBING
J 0
(-5950 3975);
DISPLAY 0.872340 (-5950 3975);
PAINT GREEN (-5950 3975);
DISPLAY INVISIBLE (-5950 3975);
FORCEPROP 1 LAST HDL_TAP TRUE
J 0
(-5625 3800);
DISPLAY 0.872340 (-5625 3800);
DISPLAY INVISIBLE (-5625 3800);
FORCEPROP 1 LAST PATH I97
J 0
(-5952 3925);
DISPLAY 0.872340 (-5952 3925);
PAINT GREEN (-5952 3925);
DISPLAY INVISIBLE (-5952 3925);
FORCEADD TAP..1
(-5950 3975);
FORCEPROP 3 LASTPIN (-6000 3975) SIG_NAME M_J_CPU0_SA_DQ<4>
J 0
(-5990 3985);
DISPLAY 0.659574 (-5990 3985);
PAINT MONO (-5990 3985);
DISPLAY INVISIBLE (-5990 3985);
FORCEPROP 1 LASTPIN (-6000 3975) BN 4
J 0
(-6012 3983);
DISPLAY 0.489362 (-6012 3983);
PAINT GREEN (-6012 3983);
FORCEPROP 2 LAST CDS_LIB mstr_standard
J 0
(-5950 3975);
DISPLAY 0.723404 (-5950 3975);
PAINT MONO (-5950 3975);
DISPLAY INVISIBLE (-5950 3975);
FORCEPROP 1 LAST BODY_TYPE PLUMBING
J 0
(-5950 4025);
DISPLAY 0.872340 (-5950 4025);
PAINT GREEN (-5950 4025);
DISPLAY INVISIBLE (-5950 4025);
FORCEPROP 1 LAST HDL_TAP TRUE
J 0
(-5625 3850);
DISPLAY 0.872340 (-5625 3850);
DISPLAY INVISIBLE (-5625 3850);
FORCEPROP 1 LAST PATH I98
J 0
(-5952 3975);
DISPLAY 0.872340 (-5952 3975);
PAINT GREEN (-5952 3975);
DISPLAY INVISIBLE (-5952 3975);
FORCEADD TAP..1
(-5950 4025);
FORCEPROP 3 LASTPIN (-6000 4025) SIG_NAME M_J_CPU0_SA_DQ<5>
J 0
(-5990 4035);
DISPLAY 0.659574 (-5990 4035);
PAINT MONO (-5990 4035);
DISPLAY INVISIBLE (-5990 4035);
FORCEPROP 1 LASTPIN (-6000 4025) BN 5
J 0
(-6012 4033);
DISPLAY 0.489362 (-6012 4033);
PAINT GREEN (-6012 4033);
FORCEPROP 2 LAST CDS_LIB mstr_standard
J 0
(-5950 4025);
DISPLAY 0.723404 (-5950 4025);
PAINT MONO (-5950 4025);
DISPLAY INVISIBLE (-5950 4025);
FORCEPROP 1 LAST BODY_TYPE PLUMBING
J 0
(-5950 4075);
DISPLAY 0.872340 (-5950 4075);
PAINT GREEN (-5950 4075);
DISPLAY INVISIBLE (-5950 4075);
FORCEPROP 1 LAST HDL_TAP TRUE
J 0
(-5625 3900);
DISPLAY 0.872340 (-5625 3900);
DISPLAY INVISIBLE (-5625 3900);
FORCEPROP 1 LAST PATH I99
J 0
(-5952 4025);
DISPLAY 0.872340 (-5952 4025);
PAINT GREEN (-5952 4025);
DISPLAY INVISIBLE (-5952 4025);
FORCEADD QUANTA_TITLE_BLOCK_C..1
(0 0);
FORCEPROP 0 LAST CDS_CON_LAST_MODIFIED Fri Mar 11 14:52:59 2022
J 0
(-1885 15);
DISPLAY INVISIBLE (-1885 15);
FORCEPROP 1 LAST CUSTOM_TXT_CDS <CON_LAST_MODIFIED>
J 0
(-1885 15);
DISPLAY 0.978723 (-1885 15);
FORCEPROP 2 LAST CUSTOM_TXT_CDS <XR_PAGE_TITLE>
J 0
(-7890 5250);
DISPLAY 0.638298 (-7890 5250);
PAINT PINK (-7890 5250);
DISPLAY INVISIBLE (-7890 5250);
FORCEPROP 1 LAST CUSTOM_TXT_CDS <NAME_2>
J 0
(-3175 50);
FORCEPROP 1 LAST CUSTOM_TXT_CDS <NAME_1>
J 0
(-3175 175);
FORCEPROP 1 LAST CUSTOM_TXT_CDS <Q_NUMBER>
J 0
(-1403 103);
DISPLAY 1.212766 (-1403 103);
FORCEPROP 1 LAST CUSTOM_TXT_CDS <Q_PROJ>
J 0
(-2382 102);
DISPLAY 1.212766 (-2382 102);
FORCEPROP 1 LAST CUSTOM_TXT_CDS <Q_REV>
J 0
(-184 103);
DISPLAY 1.212766 (-184 103);
FORCEPROP 1 LAST CUSTOM_TXT_CDS <CON_PAGE_NUM> OF <CON_TOTAL_PAGES>
J 0
(-446 18);
DISPLAY 0.978723 (-446 18);
FORCEPROP 1 LAST Q_TITLE DDR5 - CPU0 CHJ
J 0
(-9366 26);
DISPLAY 2.446809 (-9366 26);
PAINT GREEN (-9366 26);
FORCEPROP 1 LAST Q_DEPT BU9
J 1
(-3763 49);
DISPLAY 1.957447 (-3763 49);
PAINT GREEN (-3763 49);
FORCEPROP 2 LAST PAGE_BORDER TRUE
J 0
(-7890 5250);
DISPLAY 0.638298 (-7890 5250);
PAINT PINK (-7890 5250);
DISPLAY INVISIBLE (-7890 5250);
FORCEPROP 1 LAST CDS_LMAN_SYM_OUTLINE -9475,6775,100,-125
J 0
(0 0);
DISPLAY 0.468085 (0 0);
PAINT GREEN (0 0);
DISPLAY INVISIBLE (0 0);
FORCEPROP 2 LAST CDS_LIB pure_quanta
J 0
(0 0);
DISPLAY INVISIBLE (0 0);
FORCEPROP 1 LAST COMMENT_BODY TRUE
J 0
(12 -13);
DISPLAY 0.978723 (12 -13);
PAINT GREEN (12 -13);
DISPLAY INVISIBLE (12 -13);
FORCEPROP 2 LAST CDS_XR_PAGE_TITLE CR-94 : @T6G_MB_LIB.T6G(SCH_1):PAGE94
J 0
(-7890 5250);
DISPLAY 0.638298 (-7890 5250);
PAINT PINK (-7890 5250);
DISPLAY INVISIBLE (-7890 5250);
FORCEADD DNS..2
(-8300 2225);
PAINT RED (-8300 2225);
FORCEPROP 2 LAST CDS_LIB mstr_misc
J 0
(-8300 2225);
DISPLAY INVISIBLE (-8300 2225);
FORCEPROP 1 LAST COMMENT_BODY TRUE
R 1
J 0
(-8225 2000);
DISPLAY 0.872340 (-8225 2000);
PAINT PEACH (-8225 2000);
DISPLAY INVISIBLE (-8225 2000);
WIRE 17 -1 (-7700 3950)(-7700 3900);
WIRE 17 -1 (-7700 3950)(-7700 3975);
WIRE 17 -1 (-7700 3850)(-7700 3900);
WIRE 17 -1 (-7700 3850)(-7700 3800);
WIRE 17 -1 (-7700 3975)(-8200 3975);
FORCEPROP 2 LAST SIG_NAME M_J_CPU0_SA_CB<7:0>
J 0
(-8150 3985);
DISPLAY 0.489362 (-8150 3985);
WIRE 17 -1 (-7700 3750)(-7700 3800);
WIRE 17 -1 (-7700 3700)(-7700 3750);
WIRE 17 -1 (-7700 3650)(-7700 3700);
WIRE 17 -1 (-7700 3600)(-7700 3650);
WIRE 17 -1 (-7700 3500)(-7700 3450);
WIRE 17 -1 (-7700 3500)(-7700 3525);
WIRE 17 -1 (-7700 3400)(-7700 3450);
WIRE 17 -1 (-7700 3400)(-7700 3350);
WIRE 17 -1 (-7700 3525)(-8200 3525);
FORCEPROP 2 LAST SIG_NAME M_J_CPU0_SB_CB<7:0>
J 0
(-8150 3535);
DISPLAY 0.489362 (-8150 3535);
WIRE 17 -1 (-7700 5050)(-7700 5100);
WIRE 17 -1 (-7700 5100)(-7700 5150);
WIRE 17 -1 (-7700 5150)(-7700 5200);
WIRE 17 -1 (-7700 5200)(-7700 5250);
WIRE 17 -1 (-7700 5250)(-7700 5300);
WIRE 17 -1 (-7700 5300)(-7700 5350);
WIRE 17 -1 (-7700 5350)(-7700 5375);
WIRE 17 -1 (-7700 5375)(-8200 5375);
FORCEPROP 2 LAST SIG_NAME M_J_CPU0_SA_CA<6:0>
J 0
(-8185 5385);
DISPLAY 0.489362 (-8185 5385);
WIRE 17 -1 (-7700 4650)(-7700 4700);
WIRE 17 -1 (-7700 4700)(-7700 4750);
WIRE 17 -1 (-7700 4750)(-7700 4800);
WIRE 17 -1 (-7700 4800)(-7700 4850);
WIRE 17 -1 (-7700 4850)(-7700 4900);
WIRE 17 -1 (-7700 4900)(-7700 4950);
WIRE 17 -1 (-7700 4950)(-7700 4975);
WIRE 17 -1 (-7700 4975)(-8200 4975);
FORCEPROP 2 LAST SIG_NAME M_J_CPU0_SB_CA<6:0>
J 0
(-8185 4985);
DISPLAY 0.489362 (-8185 4985);
WIRE 17 -1 (-7700 3300)(-7700 3350);
WIRE 17 -1 (-7700 3250)(-7700 3300);
WIRE 17 -1 (-7700 3200)(-7700 3250);
WIRE 17 -1 (-7700 3150)(-7700 3200);
WIRE 17 -1 (-5900 5250)(-5900 5200);
WIRE 17 -1 (-5900 5300)(-5900 5250);
WIRE 17 -1 (-5900 5200)(-5900 5150);
WIRE 17 -1 (-5900 5150)(-5900 5100);
WIRE 17 -1 (-5900 5350)(-5900 5300);
WIRE 17 -1 (-5900 5375)(-5900 5350);
WIRE 17 -1 (-5900 5100)(-5900 5050);
WIRE 17 -1 (-5900 5050)(-5900 5000);
WIRE 17 -1 (-5900 5375)(-5250 5375);
FORCEPROP 2 LAST SIG_NAME M_J_CPU0_SA_DQ<31:0>
J 0
(-5835 5385);
DISPLAY 0.489362 (-5835 5385);
WIRE 17 -1 (-5900 5000)(-5900 4950);
WIRE 17 -1 (-5900 4950)(-5900 4900);
WIRE 17 -1 (-5900 4900)(-5900 4850);
WIRE 17 -1 (-5900 4850)(-5900 4800);
WIRE 17 -1 (-5900 4800)(-5900 4750);
WIRE 17 -1 (-5900 4750)(-5900 4700);
WIRE 17 -1 (-5900 4700)(-5900 4650);
WIRE 17 -1 (-5900 4650)(-5900 4600);
WIRE 17 -1 (-5900 4550)(-5900 4600);
WIRE 17 -1 (-5900 4500)(-5900 4550);
WIRE 17 -1 (-5900 4450)(-5900 4500);
WIRE 17 -1 (-5900 4400)(-5900 4450);
WIRE 17 -1 (-5900 4400)(-5900 4350);
WIRE 17 -1 (-5900 4350)(-5900 4300);
WIRE 17 -1 (-5900 4300)(-5900 4250);
WIRE 17 -1 (-5900 4250)(-5900 4200);
WIRE 17 -1 (-5900 4200)(-5900 4150);
WIRE 17 -1 (-5900 4150)(-5900 4100);
WIRE 17 -1 (-5900 4100)(-5900 4050);
WIRE 17 -1 (-5900 4050)(-5900 4000);
WIRE 17 -1 (-5900 3950)(-5900 4000);
WIRE 17 -1 (-5900 3900)(-5900 3950);
WIRE 17 -1 (-5900 3850)(-5900 3900);
WIRE 17 -1 (-5900 3800)(-5900 3850);
WIRE 17 -1 (-5900 3700)(-5900 3650);
WIRE 17 -1 (-5900 3725)(-5900 3700);
WIRE 17 -1 (-5900 3650)(-5900 3600);
WIRE 17 -1 (-5900 3600)(-5900 3550);
WIRE 17 -1 (-5900 3725)(-5250 3725);
FORCEPROP 2 LAST SIG_NAME M_J_CPU0_SB_DQ<31:0>
J 0
(-5835 3735);
DISPLAY 0.489362 (-5835 3735);
WIRE 17 -1 (-5900 3550)(-5900 3500);
WIRE 17 -1 (-5900 3500)(-5900 3450);
WIRE 17 -1 (-5900 3450)(-5900 3400);
WIRE 17 -1 (-5900 3400)(-5900 3350);
WIRE 17 -1 (-5900 3350)(-5900 3300);
WIRE 17 -1 (-5900 3300)(-5900 3250);
WIRE 17 -1 (-5900 3250)(-5900 3200);
WIRE 17 -1 (-5900 3200)(-5900 3150);
WIRE 17 -1 (-5900 3150)(-5900 3100);
WIRE 17 -1 (-5900 3100)(-5900 3050);
WIRE 17 -1 (-5900 3050)(-5900 3000);
WIRE 17 -1 (-5900 3000)(-5900 2950);
WIRE 17 -1 (-5900 2900)(-5900 2950);
WIRE 17 -1 (-5900 2850)(-5900 2900);
WIRE 17 -1 (-5900 2800)(-5900 2850);
WIRE 17 -1 (-5900 2750)(-5900 2800);
WIRE 17 -1 (-5900 2750)(-5900 2700);
WIRE 17 -1 (-5900 2700)(-5900 2650);
WIRE 17 -1 (-5900 2650)(-5900 2600);
WIRE 17 -1 (-5900 2600)(-5900 2550);
WIRE 17 -1 (-5900 2550)(-5900 2500);
WIRE 17 -1 (-5900 2500)(-5900 2450);
WIRE 17 -1 (-5900 2450)(-5900 2400);
WIRE 17 -1 (-5900 2400)(-5900 2350);
WIRE 17 -1 (-5900 2300)(-5900 2350);
WIRE 17 -1 (-5900 2250)(-5900 2300);
WIRE 17 -1 (-5900 2200)(-5900 2250);
WIRE 17 -1 (-5900 2150)(-5900 2200);
WIRE 17 -1 (-3125 4000)(-3125 3900);
WIRE 17 -1 (-3125 4100)(-3125 4000);
WIRE 17 -1 (-3125 3900)(-3125 3800);
WIRE 17 -1 (-3125 3700)(-3125 3800);
WIRE 17 -1 (-3125 4200)(-3125 4100);
WIRE 17 -1 (-3125 4225)(-3125 4200);
WIRE 17 -1 (-3125 3600)(-3125 3700);
WIRE 17 -1 (-3125 3500)(-3125 3600);
WIRE 17 -1 (-3125 4225)(-2425 4225);
FORCEPROP 2 LAST SIG_NAME M_J_CPU0_SA_DQS_DN<9:0>
J 0
(-3060 4235);
DISPLAY 0.489362 (-3060 4235);
WIRE 17 -1 (-3325 3950)(-3325 3850);
WIRE 17 -1 (-3325 4050)(-3325 3950);
WIRE 17 -1 (-3325 3750)(-3325 3850);
WIRE 17 -1 (-3325 3650)(-3325 3750);
WIRE 17 -1 (-3325 4150)(-3325 4050);
WIRE 17 -1 (-3325 4250)(-3325 4150);
WIRE 17 -1 (-3325 3550)(-3325 3650);
WIRE 17 -1 (-3325 3550)(-3325 3450);
WIRE 17 -1 (-3325 4275)(-3325 4250);
WIRE 17 -1 (-3325 4275)(-2425 4275);
FORCEPROP 2 LAST SIG_NAME M_J_CPU0_SA_DQS_DP<9:0>
J 0
(-3060 4285);
DISPLAY 0.489362 (-3060 4285);
WIRE 17 -1 (-3325 3100)(-3325 3000);
WIRE 17 -1 (-3325 3200)(-3325 3100);
WIRE 17 -1 (-3325 3000)(-3325 2900);
WIRE 17 -1 (-3325 2900)(-3325 2800);
WIRE 17 -1 (-3325 3225)(-3325 3200);
WIRE 17 -1 (-3325 3225)(-2425 3225);
FORCEPROP 2 LAST SIG_NAME M_J_CPU0_SB_DQS_DP<9:0>
J 0
(-3060 3235);
DISPLAY 0.489362 (-3060 3235);
WIRE 17 -1 (-3125 3050)(-3125 2950);
WIRE 17 -1 (-3125 3150)(-3125 3050);
WIRE 17 -1 (-3125 2950)(-3125 2850);
WIRE 17 -1 (-3125 2850)(-3125 2750);
WIRE 17 -1 (-3125 3175)(-3125 3150);
WIRE 17 -1 (-3125 3175)(-2425 3175);
FORCEPROP 2 LAST SIG_NAME M_J_CPU0_SB_DQS_DN<9:0>
J 0
(-3060 3185);
DISPLAY 0.489362 (-3060 3185);
WIRE 17 -1 (-3325 2700)(-3325 2800);
WIRE 17 -1 (-3325 2600)(-3325 2700);
WIRE 17 -1 (-3325 2500)(-3325 2600);
WIRE 17 -1 (-3125 3400)(-3125 3300);
WIRE 17 -1 (-3125 3500)(-3125 3400);
WIRE 17 -1 (-3325 3450)(-3325 3350);
WIRE 17 -1 (-3125 2350)(-3125 2250);
WIRE 17 -1 (-3125 2450)(-3125 2350);
WIRE 17 -1 (-3125 2450)(-3125 2550);
WIRE 17 -1 (-3125 2550)(-3125 2650);
WIRE 17 -1 (-3125 2650)(-3125 2750);
WIRE 17 -1 (-3325 2400)(-3325 2300);
WIRE 17 -1 (-3325 2500)(-3325 2400);
WIRE 16 -1 (-6350 1000)(-6350 1075);
WIRE 16 -1 (-8550 3000)(-8550 3075);
WIRE 16 -1 (-8325 2325)(-8325 2350);
WIRE 16 -1 (-7400 2725)(-7500 2725);
FORCEPROP 2 LAST SIG_NAME I3C_SPD_DDRJ_CPU0_SCL
J 0
(-7885 2735);
DISPLAY 0.446809 (-7885 2735);
FORCEPROP 2 LASTPROP $XRERR UNIQUE?
J 0
(-8125 2735);
DISPLAY 0.638298 (-8125 2735);
PAINT MONO (-8125 2735);
DISPLAY INVISIBLE (-8125 2735);
WIRE 16 -1 (-7500 2725)(-7500 2625);
WIRE 16 -1 (-7500 2625)(-7600 2625);
WIRE 16 -1 (-7800 2625)(-8200 2625);
FORCEPROP 2 LAST SIG_NAME I3C_SPD_DDRGL_CPU0_SCL
J 0
(-8260 2635);
DISPLAY 0.489362 (-8260 2635);
WIRE 16 -1 (-8325 2125)(-8325 2075);
WIRE 16 -1 (-8125 2075)(-8325 2075);
WIRE 16 -1 (-8325 2075)(-8350 2075);
WIRE 16 -1 (-8125 2075)(-8125 2475);
WIRE 16 -1 (-7400 2475)(-8125 2475);
FORCEPROP 2 LAST SIG_NAME PWRGD_CHJ_CPU0_DIMM
J 0
(-8000 2485);
DISPLAY 0.489362 (-8000 2485);
FORCEPROP 2 LASTPROP $XRERR UNIQUE?
J 0
(-8240 2485);
DISPLAY 0.638298 (-8240 2485);
PAINT MONO (-8240 2485);
DISPLAY INVISIBLE (-8240 2485);
WIRE 16 -1 (-7400 2775)(-8200 2775);
FORCEPROP 2 LAST SIG_NAME I3C_SPD_DDRGL_CPU0_SDA
J 0
(-8210 2785);
DISPLAY 0.489362 (-8210 2785);
WIRE 16 -1 (-7400 2825)(-8200 2825);
FORCEPROP 2 LAST SIG_NAME PD_CHJ_CPU0_DIMM_SAA
J 0
(-8175 2835);
DISPLAY 0.489362 (-8175 2835);
WIRE 16 -1 (-8450 2875)(-7400 2875);
WIRE 16 -1 (-8450 3300)(-8450 2875);
WIRE 16 -1 (-8450 3325)(-8450 3300);
WIRE 16 -1 (-8550 3300)(-8450 3300);
WIRE 16 -1 (-8550 3275)(-8550 3300);
WIRE 16 -1 (-7400 2325)(-8025 2325);
FORCEPROP 2 LAST SIG_NAME TP_CHJ_CPU0_DIMM_RFU_5
J 0
(-8035 2335);
DISPLAY 0.489362 (-8035 2335);
FORCEPROP 2 LASTPROP $XRERR UNIQUE?
J 0
(-8265 2325);
DISPLAY 0.638298 (-8265 2325);
PAINT MONO (-8265 2325);
DISPLAY INVISIBLE (-8265 2325);
WIRE 16 -1 (-7400 2375)(-8025 2375);
FORCEPROP 2 LAST SIG_NAME TP_CHJ_CPU0_DIMM_RFU_6
J 0
(-8035 2385);
DISPLAY 0.489362 (-8035 2385);
FORCEPROP 2 LASTPROP $XRERR UNIQUE?
J 0
(-8265 2375);
DISPLAY 0.638298 (-8265 2375);
PAINT MONO (-8265 2375);
DISPLAY INVISIBLE (-8265 2375);
WIRE 16 -1 (-7400 2975)(-8000 2975);
FORCEPROP 2 LAST SIG_NAME M_J_CPU0_ALERT_N
J 0
(-7985 2985);
DISPLAY 0.489362 (-7985 2985);
WIRE 16 -1 (-6200 3275)(-6000 3275);
WIRE 16 -1 (-7400 3625)(-7600 3625);
WIRE 16 -1 (-2050 5175)(-1750 5175);
WIRE 16 -1 (-2050 5225)(-2050 5175);
WIRE 16 -1 (-1750 5225)(-2050 5225);
WIRE 16 -1 (-2050 5225)(-2050 5275);
WIRE 16 -1 (-1750 5275)(-2050 5275);
WIRE 16 -1 (-2050 5275)(-2050 6025);
WIRE 16 -1 (-2175 6025)(-2050 6025);
WIRE 16 -1 (-2175 6025)(-2750 6025);
WIRE 16 -1 (-2175 6025)(-2175 5925);
WIRE 16 -1 (-2750 6025)(-2750 6100);
WIRE 16 -1 (-2750 5925)(-2750 6025);
WIRE 16 -1 (-250 1975)(-250 1925);
WIRE 16 -1 (-250 2025)(-250 1975);
WIRE 16 -1 (-250 1975)(-550 1975);
WIRE 16 -1 (-250 1925)(-250 1675);
WIRE 16 -1 (-250 1925)(-550 1925);
WIRE 16 -1 (-250 2125)(-250 2025);
WIRE 16 -1 (-250 2025)(-550 2025);
WIRE 16 -1 (-250 2175)(-250 2125);
WIRE 16 -1 (-250 2125)(-550 2125);
WIRE 16 -1 (-250 2225)(-250 2175);
WIRE 16 -1 (-250 2175)(-550 2175);
WIRE 16 -1 (-250 2275)(-250 2225);
WIRE 16 -1 (-250 2225)(-550 2225);
WIRE 16 -1 (-250 2325)(-250 2275);
WIRE 16 -1 (-250 2275)(-550 2275);
WIRE 16 -1 (-250 2375)(-250 2325);
WIRE 16 -1 (-250 2325)(-550 2325);
WIRE 16 -1 (-250 2425)(-250 2375);
WIRE 16 -1 (-250 2375)(-550 2375);
WIRE 16 -1 (-250 2475)(-250 2425);
WIRE 16 -1 (-250 2425)(-550 2425);
WIRE 16 -1 (-250 2525)(-250 2475);
WIRE 16 -1 (-250 2475)(-550 2475);
WIRE 16 -1 (-250 2575)(-250 2525);
WIRE 16 -1 (-250 2525)(-550 2525);
WIRE 16 -1 (-250 2625)(-250 2575);
WIRE 16 -1 (-250 2575)(-550 2575);
WIRE 16 -1 (-250 2675)(-250 2625);
WIRE 16 -1 (-250 2625)(-550 2625);
WIRE 16 -1 (-250 2725)(-250 2675);
WIRE 16 -1 (-250 2675)(-550 2675);
WIRE 16 -1 (-250 2775)(-250 2725);
WIRE 16 -1 (-250 2725)(-550 2725);
WIRE 16 -1 (-250 2825)(-250 2775);
WIRE 16 -1 (-250 2775)(-550 2775);
WIRE 16 -1 (-250 2875)(-250 2825);
WIRE 16 -1 (-250 2825)(-550 2825);
WIRE 16 -1 (-250 2925)(-250 2875);
WIRE 16 -1 (-250 2875)(-550 2875);
WIRE 16 -1 (-250 2975)(-250 2925);
WIRE 16 -1 (-250 2925)(-550 2925);
WIRE 16 -1 (-250 3025)(-250 2975);
WIRE 16 -1 (-250 2975)(-550 2975);
WIRE 16 -1 (-250 3075)(-250 3025);
WIRE 16 -1 (-250 3025)(-550 3025);
WIRE 16 -1 (-250 3125)(-250 3075);
WIRE 16 -1 (-250 3075)(-550 3075);
WIRE 16 -1 (-250 3175)(-250 3125);
WIRE 16 -1 (-250 3125)(-550 3125);
WIRE 16 -1 (-250 3225)(-250 3175);
WIRE 16 -1 (-250 3175)(-550 3175);
WIRE 16 -1 (-250 3275)(-250 3225);
WIRE 16 -1 (-250 3225)(-550 3225);
WIRE 16 -1 (-250 3325)(-250 3275);
WIRE 16 -1 (-250 3275)(-550 3275);
WIRE 16 -1 (-250 3375)(-250 3325);
WIRE 16 -1 (-250 3325)(-550 3325);
WIRE 16 -1 (-250 3425)(-250 3375);
WIRE 16 -1 (-250 3375)(-550 3375);
WIRE 16 -1 (-250 3475)(-250 3425);
WIRE 16 -1 (-250 3425)(-550 3425);
WIRE 16 -1 (-250 3525)(-250 3475);
WIRE 16 -1 (-250 3475)(-550 3475);
WIRE 16 -1 (-250 3575)(-250 3525);
WIRE 16 -1 (-250 3525)(-550 3525);
WIRE 16 -1 (-250 3625)(-250 3575);
WIRE 16 -1 (-250 3575)(-550 3575);
WIRE 16 -1 (-250 3675)(-250 3625);
WIRE 16 -1 (-250 3625)(-550 3625);
WIRE 16 -1 (-250 3725)(-250 3675);
WIRE 16 -1 (-250 3675)(-550 3675);
WIRE 16 -1 (-250 3775)(-250 3725);
WIRE 16 -1 (-250 3725)(-550 3725);
WIRE 16 -1 (-250 3825)(-250 3775);
WIRE 16 -1 (-250 3775)(-550 3775);
WIRE 16 -1 (-250 3875)(-250 3825);
WIRE 16 -1 (-250 3825)(-550 3825);
WIRE 16 -1 (-250 3925)(-250 3875);
WIRE 16 -1 (-250 3875)(-550 3875);
WIRE 16 -1 (-250 3975)(-250 3925);
WIRE 16 -1 (-250 3925)(-550 3925);
WIRE 16 -1 (-250 4025)(-250 3975);
WIRE 16 -1 (-250 3975)(-550 3975);
WIRE 16 -1 (-250 4075)(-250 4025);
WIRE 16 -1 (-250 4025)(-550 4025);
WIRE 16 -1 (-250 4125)(-250 4075);
WIRE 16 -1 (-250 4075)(-550 4075);
WIRE 16 -1 (-250 4175)(-250 4125);
WIRE 16 -1 (-250 4125)(-550 4125);
WIRE 16 -1 (-250 4225)(-250 4175);
WIRE 16 -1 (-250 4175)(-550 4175);
WIRE 16 -1 (-250 4275)(-250 4225);
WIRE 16 -1 (-250 4225)(-550 4225);
WIRE 16 -1 (-250 4325)(-250 4275);
WIRE 16 -1 (-250 4275)(-550 4275);
WIRE 16 -1 (-250 4375)(-250 4325);
WIRE 16 -1 (-250 4325)(-550 4325);
WIRE 16 -1 (-250 4425)(-250 4375);
WIRE 16 -1 (-250 4375)(-550 4375);
WIRE 16 -1 (-250 4475)(-250 4425);
WIRE 16 -1 (-250 4425)(-550 4425);
WIRE 16 -1 (-250 4525)(-250 4475);
WIRE 16 -1 (-250 4475)(-550 4475);
WIRE 16 -1 (-250 4575)(-250 4525);
WIRE 16 -1 (-250 4525)(-550 4525);
WIRE 16 -1 (-250 4625)(-250 4575);
WIRE 16 -1 (-250 4575)(-550 4575);
WIRE 16 -1 (-250 4675)(-250 4625);
WIRE 16 -1 (-250 4625)(-550 4625);
WIRE 16 -1 (-250 4725)(-250 4675);
WIRE 16 -1 (-250 4675)(-550 4675);
WIRE 16 -1 (-250 4775)(-250 4725);
WIRE 16 -1 (-250 4725)(-550 4725);
WIRE 16 -1 (-250 4825)(-250 4775);
WIRE 16 -1 (-250 4775)(-550 4775);
WIRE 16 -1 (-250 4875)(-250 4825);
WIRE 16 -1 (-250 4825)(-550 4825);
WIRE 16 -1 (-250 4925)(-250 4875);
WIRE 16 -1 (-250 4875)(-550 4875);
WIRE 16 -1 (-250 4975)(-250 4925);
WIRE 16 -1 (-250 4925)(-550 4925);
WIRE 16 -1 (-250 5025)(-250 4975);
WIRE 16 -1 (-250 4975)(-550 4975);
WIRE 16 -1 (-250 5075)(-250 5025);
WIRE 16 -1 (-250 5025)(-550 5025);
WIRE 16 -1 (-250 5125)(-250 5075);
WIRE 16 -1 (-250 5075)(-550 5075);
WIRE 16 -1 (-250 5175)(-250 5125);
WIRE 16 -1 (-250 5125)(-550 5125);
WIRE 16 -1 (-250 5225)(-250 5175);
WIRE 16 -1 (-250 5175)(-550 5175);
WIRE 16 -1 (-250 5275)(-250 5225);
WIRE 16 -1 (-250 5225)(-550 5225);
WIRE 16 -1 (-250 5275)(-550 5275);
WIRE 16 -1 (-1750 2025)(-2050 2025);
WIRE 16 -1 (-2050 2075)(-2050 2025);
WIRE 16 -1 (-2050 2025)(-2050 1900);
WIRE 16 -1 (-1750 2075)(-2050 2075);
WIRE 16 -1 (-2050 2125)(-2050 2075);
WIRE 16 -1 (-1750 2125)(-2050 2125);
WIRE 16 -1 (-2050 2175)(-2050 2125);
WIRE 16 -1 (-1750 2175)(-2050 2175);
WIRE 16 -1 (-2050 2225)(-2050 2175);
WIRE 16 -1 (-1750 2225)(-2050 2225);
WIRE 16 -1 (-2050 2275)(-2050 2225);
WIRE 16 -1 (-1750 2275)(-2050 2275);
WIRE 16 -1 (-2050 2325)(-2050 2275);
WIRE 16 -1 (-1750 2325)(-2050 2325);
WIRE 16 -1 (-2050 2375)(-2050 2325);
WIRE 16 -1 (-1750 2375)(-2050 2375);
WIRE 16 -1 (-2050 2425)(-2050 2375);
WIRE 16 -1 (-1750 2425)(-2050 2425);
WIRE 16 -1 (-2050 2475)(-2050 2425);
WIRE 16 -1 (-1750 2475)(-2050 2475);
WIRE 16 -1 (-2050 2525)(-2050 2475);
WIRE 16 -1 (-1750 2525)(-2050 2525);
WIRE 16 -1 (-2050 2575)(-2050 2525);
WIRE 16 -1 (-1750 2575)(-2050 2575);
WIRE 16 -1 (-2050 2625)(-2050 2575);
WIRE 16 -1 (-1750 2625)(-2050 2625);
WIRE 16 -1 (-2050 2675)(-2050 2625);
WIRE 16 -1 (-1750 2675)(-2050 2675);
WIRE 16 -1 (-2050 2725)(-2050 2675);
WIRE 16 -1 (-1750 2725)(-2050 2725);
WIRE 16 -1 (-2050 2775)(-2050 2725);
WIRE 16 -1 (-1750 2775)(-2050 2775);
WIRE 16 -1 (-2050 2825)(-2050 2775);
WIRE 16 -1 (-1750 2825)(-2050 2825);
WIRE 16 -1 (-2050 2875)(-2050 2825);
WIRE 16 -1 (-1750 2875)(-2050 2875);
WIRE 16 -1 (-2050 2925)(-2050 2875);
WIRE 16 -1 (-1750 2925)(-2050 2925);
WIRE 16 -1 (-2050 2975)(-2050 2925);
WIRE 16 -1 (-1750 2975)(-2050 2975);
WIRE 16 -1 (-2050 3025)(-2050 2975);
WIRE 16 -1 (-1750 3025)(-2050 3025);
WIRE 16 -1 (-2050 3075)(-2050 3025);
WIRE 16 -1 (-1750 3075)(-2050 3075);
WIRE 16 -1 (-2050 3125)(-2050 3075);
WIRE 16 -1 (-1750 3125)(-2050 3125);
WIRE 16 -1 (-2050 3175)(-2050 3125);
WIRE 16 -1 (-1750 3175)(-2050 3175);
WIRE 16 -1 (-2050 3225)(-2050 3175);
WIRE 16 -1 (-1750 3225)(-2050 3225);
WIRE 16 -1 (-2050 3275)(-2050 3225);
WIRE 16 -1 (-1750 3275)(-2050 3275);
WIRE 16 -1 (-2050 3325)(-2050 3275);
WIRE 16 -1 (-1750 3325)(-2050 3325);
WIRE 16 -1 (-2050 3375)(-2050 3325);
WIRE 16 -1 (-1750 3375)(-2050 3375);
WIRE 16 -1 (-2050 3425)(-2050 3375);
WIRE 16 -1 (-1750 3425)(-2050 3425);
WIRE 16 -1 (-2050 3475)(-2050 3425);
WIRE 16 -1 (-1750 3475)(-2050 3475);
WIRE 16 -1 (-2050 3525)(-2050 3475);
WIRE 16 -1 (-1750 3525)(-2050 3525);
WIRE 16 -1 (-2050 3575)(-2050 3525);
WIRE 16 -1 (-1750 3575)(-2050 3575);
WIRE 16 -1 (-2050 3625)(-2050 3575);
WIRE 16 -1 (-1750 3625)(-2050 3625);
WIRE 16 -1 (-2050 3675)(-2050 3625);
WIRE 16 -1 (-1750 3675)(-2050 3675);
WIRE 16 -1 (-2050 3725)(-2050 3675);
WIRE 16 -1 (-1750 3725)(-2050 3725);
WIRE 16 -1 (-2050 3775)(-2050 3725);
WIRE 16 -1 (-1750 3775)(-2050 3775);
WIRE 16 -1 (-2050 3825)(-2050 3775);
WIRE 16 -1 (-1750 3825)(-2050 3825);
WIRE 16 -1 (-2050 3875)(-2050 3825);
WIRE 16 -1 (-1750 3875)(-2050 3875);
WIRE 16 -1 (-2050 3925)(-2050 3875);
WIRE 16 -1 (-1750 3925)(-2050 3925);
WIRE 16 -1 (-2050 3975)(-2050 3925);
WIRE 16 -1 (-1750 3975)(-2050 3975);
WIRE 16 -1 (-2050 4025)(-2050 3975);
WIRE 16 -1 (-1750 4025)(-2050 4025);
WIRE 16 -1 (-2050 4075)(-2050 4025);
WIRE 16 -1 (-2050 4125)(-2050 4075);
WIRE 16 -1 (-1750 4075)(-2050 4075);
WIRE 16 -1 (-1750 4125)(-2050 4125);
WIRE 16 -1 (-2050 4175)(-2050 4125);
WIRE 16 -1 (-1750 4175)(-2050 4175);
WIRE 16 -1 (-2050 4225)(-2050 4175);
WIRE 16 -1 (-1750 4225)(-2050 4225);
WIRE 16 -1 (-2050 4275)(-2050 4225);
WIRE 16 -1 (-1750 4275)(-2050 4275);
WIRE 16 -1 (-2050 4325)(-2050 4275);
WIRE 16 -1 (-1750 4325)(-2050 4325);
WIRE 16 -1 (-2050 4375)(-2050 4325);
WIRE 16 -1 (-1750 4375)(-2050 4375);
WIRE 16 -1 (-2050 4425)(-2050 4375);
WIRE 16 -1 (-1750 4425)(-2050 4425);
WIRE 16 -1 (-2050 4475)(-2050 4425);
WIRE 16 -1 (-1750 4475)(-2050 4475);
WIRE 16 -1 (-2050 4525)(-2050 4475);
WIRE 16 -1 (-1750 4525)(-2050 4525);
WIRE 16 -1 (-2050 4575)(-2050 4525);
WIRE 16 -1 (-1750 4575)(-2050 4575);
WIRE 16 -1 (-2050 4625)(-2050 4575);
WIRE 16 -1 (-1750 4625)(-2050 4625);
WIRE 16 -1 (-2050 4675)(-2050 4625);
WIRE 16 -1 (-1750 4675)(-2050 4675);
WIRE 16 -1 (-2050 4725)(-2050 4675);
WIRE 16 -1 (-1750 4725)(-2050 4725);
WIRE 16 -1 (-2050 4775)(-2050 4725);
WIRE 16 -1 (-1750 4775)(-2050 4775);
WIRE 16 -1 (-2050 4825)(-2050 4775);
WIRE 16 -1 (-1750 4825)(-2050 4825);
WIRE 16 -1 (-2050 4875)(-2050 4825);
WIRE 16 -1 (-1750 4875)(-2050 4875);
WIRE 16 -1 (-2050 4925)(-2050 4875);
WIRE 16 -1 (-1750 4925)(-2050 4925);
WIRE 16 -1 (-2050 4975)(-2050 4925);
WIRE 16 -1 (-1750 4975)(-2050 4975);
WIRE 16 -1 (-2050 5025)(-2050 4975);
WIRE 16 -1 (-1750 5025)(-2050 5025);
WIRE 16 -1 (-2050 5075)(-2050 5025);
WIRE 16 -1 (-1750 5075)(-2050 5075);
WIRE 16 -1 (-2050 5125)(-2050 5075);
WIRE 16 -1 (-1750 5125)(-2050 5125);
WIRE 16 -1 (-3575 3175)(-3425 3175);
WIRE 16 -1 (-3575 3125)(-3225 3125);
WIRE 16 -1 (-3575 4225)(-3425 4225);
WIRE 16 -1 (-3575 4175)(-3225 4175);
WIRE 16 -1 (-3425 4125)(-3575 4125);
WIRE 16 -1 (-3575 4075)(-3225 4075);
WIRE 16 -1 (-3575 2925)(-3225 2925);
WIRE 16 -1 (-3425 4025)(-3575 4025);
WIRE 16 -1 (-3425 2875)(-3575 2875);
WIRE 16 -1 (-3575 2825)(-3225 2825);
WIRE 16 -1 (-3575 3875)(-3225 3875);
WIRE 16 -1 (-3575 2775)(-3425 2775);
WIRE 16 -1 (-3575 2725)(-3225 2725);
WIRE 16 -1 (-3575 3825)(-3425 3825);
WIRE 16 -1 (-3225 3775)(-3575 3775);
WIRE 16 -1 (-3425 2675)(-3575 2675);
WIRE 16 -1 (-3575 2625)(-3225 2625);
WIRE 16 -1 (-3425 3725)(-3575 3725);
WIRE 16 -1 (-3575 3675)(-3225 3675);
WIRE 16 -1 (-3425 2575)(-3575 2575);
WIRE 16 -1 (-3575 2525)(-3225 2525);
WIRE 16 -1 (-3425 3625)(-3575 3625);
WIRE 16 -1 (-3575 3575)(-3225 3575);
WIRE 16 -1 (-3425 2475)(-3575 2475);
WIRE 16 -1 (-3575 2425)(-3225 2425);
WIRE 16 -1 (-3425 3525)(-3575 3525);
WIRE 16 -1 (-3575 3475)(-3225 3475);
WIRE 16 -1 (-3575 2375)(-3425 2375);
WIRE 16 -1 (-3575 2325)(-3225 2325);
WIRE 16 -1 (-3575 3425)(-3425 3425);
WIRE 16 -1 (-3575 3375)(-3225 3375);
WIRE 16 -1 (-3425 2275)(-3575 2275);
WIRE 16 -1 (-3575 2225)(-3225 2225);
WIRE 16 -1 (-3425 3325)(-3575 3325);
WIRE 16 -1 (-3575 3275)(-3225 3275);
WIRE 16 -1 (-3425 2975)(-3575 2975);
WIRE 16 -1 (-3575 3025)(-3225 3025);
WIRE 16 -1 (-3425 3075)(-3575 3075);
WIRE 16 -1 (-3425 3925)(-3575 3925);
WIRE 16 -1 (-3575 3975)(-3225 3975);
WIRE 16 -1 (-6200 5325)(-6000 5325);
WIRE 16 -1 (-6000 5275)(-6200 5275);
WIRE 16 -1 (-7400 2075)(-8025 2075);
FORCEPROP 2 LAST SIG_NAME TP_CHJ_CPU0_DIMM_RFU_0
J 0
(-8035 2085);
DISPLAY 0.489362 (-8035 2085);
FORCEPROP 2 LASTPROP $XRERR UNIQUE?
J 0
(-8265 2075);
DISPLAY 0.638298 (-8265 2075);
PAINT MONO (-8265 2075);
DISPLAY INVISIBLE (-8265 2075);
WIRE 16 -1 (-7400 2125)(-8025 2125);
FORCEPROP 2 LAST SIG_NAME TP_CHJ_CPU0_DIMM_RFU_1
J 0
(-8035 2135);
DISPLAY 0.489362 (-8035 2135);
FORCEPROP 2 LASTPROP $XRERR UNIQUE?
J 0
(-8265 2125);
DISPLAY 0.638298 (-8265 2125);
PAINT MONO (-8265 2125);
DISPLAY INVISIBLE (-8265 2125);
WIRE 16 -1 (-7400 2175)(-8025 2175);
FORCEPROP 2 LAST SIG_NAME TP_CHJ_CPU0_DIMM_RFU_2
J 0
(-8035 2185);
DISPLAY 0.489362 (-8035 2185);
FORCEPROP 2 LASTPROP $XRERR UNIQUE?
J 0
(-8265 2175);
DISPLAY 0.638298 (-8265 2175);
PAINT MONO (-8265 2175);
DISPLAY INVISIBLE (-8265 2175);
WIRE 16 -1 (-7400 2225)(-8025 2225);
FORCEPROP 2 LAST SIG_NAME TP_CHJ_CPU0_DIMM_RFU_3
J 0
(-8035 2235);
DISPLAY 0.489362 (-8035 2235);
FORCEPROP 2 LASTPROP $XRERR UNIQUE?
J 0
(-8265 2225);
DISPLAY 0.638298 (-8265 2225);
PAINT MONO (-8265 2225);
DISPLAY INVISIBLE (-8265 2225);
WIRE 16 -1 (-7400 2275)(-8025 2275);
FORCEPROP 2 LAST SIG_NAME TP_CHJ_CPU0_DIMM_RFU_4
J 0
(-8035 2285);
DISPLAY 0.489362 (-8035 2285);
FORCEPROP 2 LASTPROP $XRERR UNIQUE?
J 0
(-8265 2275);
DISPLAY 0.638298 (-8265 2275);
PAINT MONO (-8265 2275);
DISPLAY INVISIBLE (-8265 2275);
WIRE 16 -1 (-7400 3025)(-8000 3025);
FORCEPROP 2 LAST SIG_NAME M_J_CPU0_RESET_N
J 0
(-7985 3035);
DISPLAY 0.489362 (-7985 3035);
WIRE 16 -1 (-7400 4475)(-8200 4475);
FORCEPROP 2 LAST SIG_NAME M_J_CPU0_SB_PAR
J 0
(-8150 4485);
DISPLAY 0.489362 (-8150 4485);
WIRE 16 -1 (-7400 4525)(-8200 4525);
FORCEPROP 2 LAST SIG_NAME M_J_CPU0_SA_PAR
J 0
(-8150 4535);
DISPLAY 0.489362 (-8150 4535);
WIRE 16 -1 (-7400 1875)(-8200 1875);
FORCEPROP 2 LAST SIG_NAME M_J_CPU0_SB_RSP<0>
J 0
(-8150 1885);
DISPLAY 0.489362 (-8150 1885);
WIRE 16 -1 (-7400 1925)(-8200 1925);
FORCEPROP 2 LAST SIG_NAME M_J_CPU0_SA_RSP<0>
J 0
(-8150 1935);
DISPLAY 0.489362 (-8150 1935);
WIRE 16 -1 (-6000 2125)(-6200 2125);
WIRE 16 -1 (-6000 2175)(-6200 2175);
WIRE 16 -1 (-6000 2225)(-6200 2225);
WIRE 16 -1 (-6200 2275)(-6000 2275);
WIRE 16 -1 (-6000 2325)(-6200 2325);
WIRE 16 -1 (-6000 2375)(-6200 2375);
WIRE 16 -1 (-6000 2425)(-6200 2425);
WIRE 16 -1 (-6200 2475)(-6000 2475);
WIRE 16 -1 (-6000 2525)(-6200 2525);
WIRE 16 -1 (-6000 2575)(-6200 2575);
WIRE 16 -1 (-6000 2625)(-6200 2625);
WIRE 16 -1 (-6200 2675)(-6000 2675);
WIRE 16 -1 (-6000 2725)(-6200 2725);
WIRE 16 -1 (-6000 2775)(-6200 2775);
WIRE 16 -1 (-6000 2825)(-6200 2825);
WIRE 16 -1 (-6200 2875)(-6000 2875);
WIRE 16 -1 (-6000 2925)(-6200 2925);
WIRE 16 -1 (-6000 2975)(-6200 2975);
WIRE 16 -1 (-6000 3025)(-6200 3025);
WIRE 16 -1 (-6200 3075)(-6000 3075);
WIRE 16 -1 (-6000 3125)(-6200 3125);
WIRE 16 -1 (-6000 3175)(-6200 3175);
WIRE 16 -1 (-6000 3225)(-6200 3225);
WIRE 16 -1 (-6000 3325)(-6200 3325);
WIRE 16 -1 (-6000 3375)(-6200 3375);
WIRE 16 -1 (-6000 3425)(-6200 3425);
WIRE 16 -1 (-6200 3475)(-6000 3475);
WIRE 16 -1 (-6000 3525)(-6200 3525);
WIRE 16 -1 (-6000 3575)(-6200 3575);
WIRE 16 -1 (-6000 3625)(-6200 3625);
WIRE 16 -1 (-6200 3675)(-6000 3675);
WIRE 16 -1 (-6000 3775)(-6200 3775);
WIRE 16 -1 (-6000 3825)(-6200 3825);
WIRE 16 -1 (-6000 3875)(-6200 3875);
WIRE 16 -1 (-6200 3925)(-6000 3925);
WIRE 16 -1 (-6000 3975)(-6200 3975);
WIRE 16 -1 (-6000 4025)(-6200 4025);
WIRE 16 -1 (-6000 4075)(-6200 4075);
WIRE 16 -1 (-6200 4125)(-6000 4125);
WIRE 16 -1 (-6000 4175)(-6200 4175);
WIRE 16 -1 (-6000 4225)(-6200 4225);
WIRE 16 -1 (-6000 4275)(-6200 4275);
WIRE 16 -1 (-6200 4325)(-6000 4325);
WIRE 16 -1 (-6000 4375)(-6200 4375);
WIRE 16 -1 (-6000 4425)(-6200 4425);
WIRE 16 -1 (-6000 4475)(-6200 4475);
WIRE 16 -1 (-6200 4525)(-6000 4525);
WIRE 16 -1 (-6000 4575)(-6200 4575);
WIRE 16 -1 (-6000 4625)(-6200 4625);
WIRE 16 -1 (-6000 4675)(-6200 4675);
WIRE 16 -1 (-6200 4725)(-6000 4725);
WIRE 16 -1 (-6000 4775)(-6200 4775);
WIRE 16 -1 (-6000 4825)(-6200 4825);
WIRE 16 -1 (-6000 4875)(-6200 4875);
WIRE 16 -1 (-6200 4925)(-6000 4925);
WIRE 16 -1 (-6000 4975)(-6200 4975);
WIRE 16 -1 (-6000 5025)(-6200 5025);
WIRE 16 -1 (-6000 5075)(-6200 5075);
WIRE 16 -1 (-6200 5125)(-6000 5125);
WIRE 16 -1 (-6000 5175)(-6200 5175);
WIRE 16 -1 (-6000 5225)(-6200 5225);
WIRE 16 -1 (-7400 4225)(-8200 4225);
FORCEPROP 2 LAST SIG_NAME M_J_CPU0_SB_CS_N<1>
J 0
(-8150 4235);
DISPLAY 0.489362 (-8150 4235);
WIRE 16 -1 (-7400 4375)(-8200 4375);
FORCEPROP 2 LAST SIG_NAME M_J_CPU0_SA_CS_N<1>
J 0
(-8150 4385);
DISPLAY 0.489362 (-8150 4385);
WIRE 16 -1 (-7400 4175)(-8200 4175);
FORCEPROP 2 LAST SIG_NAME M_J_CPU0_SB_CS_N<0>
J 0
(-8150 4185);
DISPLAY 0.489362 (-8150 4185);
WIRE 16 -1 (-7400 4325)(-8200 4325);
FORCEPROP 2 LAST SIG_NAME M_J_CPU0_SA_CS_N<0>
J 0
(-8150 4335);
DISPLAY 0.489362 (-8150 4335);
WIRE 16 -1 (-7400 4075)(-8200 4075);
FORCEPROP 2 LAST SIG_NAME M_J_CPU0_CLK_DP<0>
J 0
(-8150 4085);
DISPLAY 0.489362 (-8150 4085);
WIRE 16 -1 (-7400 4025)(-8200 4025);
FORCEPROP 2 LAST SIG_NAME M_J_CPU0_CLK_DN<0>
J 0
(-8150 4035);
DISPLAY 0.489362 (-8150 4035);
WIRE 16 -1 (-7400 3125)(-7600 3125);
WIRE 16 -1 (-7400 3175)(-7600 3175);
WIRE 16 -1 (-7400 3225)(-7600 3225);
WIRE 16 -1 (-7400 3275)(-7600 3275);
WIRE 16 -1 (-7400 3325)(-7600 3325);
WIRE 16 -1 (-7400 3375)(-7600 3375);
WIRE 16 -1 (-7400 3425)(-7600 3425);
WIRE 16 -1 (-7400 3575)(-7600 3575);
WIRE 16 -1 (-7400 3675)(-7600 3675);
WIRE 16 -1 (-7400 3725)(-7600 3725);
WIRE 16 -1 (-7400 3825)(-7600 3825);
WIRE 16 -1 (-7400 3875)(-7600 3875);
WIRE 16 -1 (-7400 4925)(-7600 4925);
WIRE 16 -1 (-7400 5325)(-7600 5325);
WIRE 16 -1 (-7400 4875)(-7600 4875);
WIRE 16 -1 (-7400 5275)(-7600 5275);
WIRE 16 -1 (-7400 4825)(-7600 4825);
WIRE 16 -1 (-7400 5225)(-7600 5225);
WIRE 16 -1 (-7400 4775)(-7600 4775);
WIRE 16 -1 (-7400 5175)(-7600 5175);
WIRE 16 -1 (-7400 4725)(-7600 4725);
WIRE 16 -1 (-7400 5125)(-7600 5125);
WIRE 16 -1 (-7400 4675)(-7600 4675);
WIRE 16 -1 (-7400 5075)(-7600 5075);
WIRE 16 -1 (-7400 4625)(-7600 4625);
WIRE 16 -1 (-7400 5025)(-7600 5025);
WIRE 16 -1 (-7400 3475)(-7600 3475);
WIRE 16 -1 (-7400 3775)(-7600 3775);
WIRE 16 -1 (-7400 3925)(-7600 3925);
WIRE 16 -1 (-2175 5600)(-2750 5600);
WIRE 16 -1 (-2175 5600)(-2175 5725);
WIRE 16 -1 (-2750 5600)(-2750 5725);
WIRE 16 -1 (-2750 5600)(-2750 5525);
WIRE 16 -1 (-8950 2075)(-8550 2075);
FORCEPROP 2 LAST SIG_NAME PWRGD_CHGL_CPU0
J 0
(-8935 2085);
DISPLAY 0.489362 (-8935 2085);
WIRE 16 -1 (-6350 1350)(-6350 1275);
WIRE 16 -1 (-6350 1350)(-7075 1350);
FORCEPROP 2 LAST SIG_NAME PD_CHJ_CPU0_DIMM_SAA
J 0
(-7060 1360);
DISPLAY 0.489362 (-7060 1360);
DOT 1 (-2175 6025);
DOT 1 (-2750 6025);
DOT 1 (-2750 5600);
DOT 1 (-8450 3300);
DOT 1 (-2050 2075);
DOT 1 (-2050 2025);
DOT 1 (-2050 2225);
DOT 1 (-2050 2175);
DOT 1 (-2050 2125);
DOT 1 (-2050 2325);
DOT 1 (-2050 2275);
DOT 1 (-2050 2475);
DOT 1 (-2050 2425);
DOT 1 (-2050 2375);
DOT 1 (-2050 2575);
DOT 1 (-2050 2525);
DOT 1 (-2050 2625);
DOT 1 (-2050 2675);
DOT 1 (-2050 2725);
DOT 1 (-2050 2825);
DOT 1 (-2050 2775);
DOT 1 (-2050 2875);
DOT 1 (-2050 2975);
DOT 1 (-2050 2925);
DOT 1 (-2050 3125);
DOT 1 (-2050 3075);
DOT 1 (-2050 3025);
DOT 1 (-2050 3225);
DOT 1 (-2050 3175);
DOT 1 (-2050 3375);
DOT 1 (-2050 3325);
DOT 1 (-2050 3275);
DOT 1 (-2050 3475);
DOT 1 (-2050 3425);
DOT 1 (-2050 3525);
DOT 1 (-2050 3625);
DOT 1 (-2050 3575);
DOT 1 (-2050 3725);
DOT 1 (-2050 3675);
DOT 1 (-2050 3775);
DOT 1 (-2050 3825);
DOT 1 (-2050 3875);
DOT 1 (-250 1975);
DOT 1 (-250 1925);
DOT 1 (-250 2025);
DOT 1 (-250 2225);
DOT 1 (-250 2175);
DOT 1 (-250 2125);
DOT 1 (-250 2325);
DOT 1 (-250 2275);
DOT 1 (-250 2425);
DOT 1 (-250 2475);
DOT 1 (-250 2375);
DOT 1 (-250 2575);
DOT 1 (-250 2525);
DOT 1 (-250 2625);
DOT 1 (-250 2725);
DOT 1 (-250 2675);
DOT 1 (-250 2825);
DOT 1 (-250 2775);
DOT 1 (-250 2875);
DOT 1 (-250 2975);
DOT 1 (-250 2925);
DOT 1 (-250 3075);
DOT 1 (-250 3125);
DOT 1 (-250 3025);
DOT 1 (-250 3225);
DOT 1 (-250 3175);
DOT 1 (-250 3325);
DOT 1 (-250 3375);
DOT 1 (-250 3275);
DOT 1 (-250 3475);
DOT 1 (-250 3425);
DOT 1 (-250 3525);
DOT 1 (-250 3625);
DOT 1 (-250 3575);
DOT 1 (-250 3725);
DOT 1 (-250 3675);
DOT 1 (-250 3775);
DOT 1 (-250 3875);
DOT 1 (-250 3825);
DOT 1 (-2050 3925);
DOT 1 (-2050 3975);
DOT 1 (-2050 4025);
DOT 1 (-2050 4125);
DOT 1 (-2050 4075);
DOT 1 (-2050 4275);
DOT 1 (-2050 4225);
DOT 1 (-2050 4375);
DOT 1 (-2050 4525);
DOT 1 (-2050 4475);
DOT 1 (-2050 4425);
DOT 1 (-2050 4625);
DOT 1 (-2050 4575);
DOT 1 (-2050 4675);
DOT 1 (-2050 4725);
DOT 1 (-2050 4775);
DOT 1 (-2050 4875);
DOT 1 (-2050 4825);
DOT 1 (-2050 4925);
DOT 1 (-2050 5025);
DOT 1 (-2050 4975);
DOT 1 (-2050 5075);
DOT 1 (-2050 5225);
DOT 1 (-250 3975);
DOT 1 (-250 3925);
DOT 1 (-250 4025);
DOT 1 (-250 4125);
DOT 1 (-250 4075);
DOT 1 (-250 4225);
DOT 1 (-250 4275);
DOT 1 (-250 4175);
DOT 1 (-250 4375);
DOT 1 (-250 4325);
DOT 1 (-250 4475);
DOT 1 (-250 4525);
DOT 1 (-250 4425);
DOT 1 (-250 4625);
DOT 1 (-250 4575);
DOT 1 (-250 4675);
DOT 1 (-250 4775);
DOT 1 (-250 4725);
DOT 1 (-250 4875);
DOT 1 (-250 4825);
DOT 1 (-250 4925);
DOT 1 (-250 5025);
DOT 1 (-250 4975);
DOT 1 (-250 5125);
DOT 1 (-250 5075);
DOT 1 (-250 5175);
DOT 1 (-250 5225);
DOT 1 (-2050 4175);
DOT 1 (-2050 4325);
DOT 1 (-2050 5275);
DOT 1 (-8325 2075);
QUIT
